FILE_TYPE = MACRO_DRAWING;
SET COLOR_WIRE YELLOW;
SET COLOR_PROP ORANGE;
SET COLOR_DOT WHITE;
SET COLOR_ARC YELLOW;
SET COLOR_BODY GREEN;
SET COLOR_NOTE PURPLE;
SET PROP_DISPLAY VALUE;
SET PAGE_NUMBER P341;
FORCEADD UNIVERSAL_GND..1
(275 -450);
FORCEPROP 3 LASTPIN (275 -400) SIG_NAME GND\g
J 0
(285 -390);
DISPLAY 0.659574 (285 -390);
PAINT MONO (285 -390);
DISPLAY INVISIBLE (285 -390);
FORCEPROP 2 LAST ROOM IO_SLOT
J 1
(50 -375);
DISPLAY 0.744681 (50 -375);
FORCEPROP 2 LAST CDS_LIB pure_quanta_power
J 0
(275 -450);
PAINT MONO (275 -450);
DISPLAY INVISIBLE (275 -450);
FORCEPROP 1 LAST HDL_POWER GND
J 1
(300 -525);
DISPLAY 0.872340 (300 -525);
PAINT GREEN (300 -525);
DISPLAY INVISIBLE (300 -525);
FORCEPROP 1 LAST PATH I1
J 0
(350 -450);
DISPLAY 0.872340 (350 -450);
PAINT AQUA (350 -450);
DISPLAY INVISIBLE (350 -450);
FORCEADD Q_RES..1
(3650 -100);
FORCEPROP 1 LAST LOCATION R3173
J 0
(3425 -100);
DISPLAY 0.787234 (3425 -100);
FORCEPROP 2 LAST $SEC 1
J 0
(3600 100);
DISPLAY 0.680851 (3600 100);
PAINT MONO (3600 100);
DISPLAY INVISIBLE (3600 100);
FORCEPROP 2 LAST CDS_SEC 1
J 0
(3600 100);
DISPLAY 1.021277 (3600 100);
DISPLAY INVISIBLE (3600 100);
FORCEPROP 1 LASTPIN (3550 -100) $PN 1
J 0
(3562 -88);
DISPLAY 0.787234 (3562 -88);
FORCEPROP 1 LASTPIN (3750 -100) $PN 2
J 0
(3712 -88);
DISPLAY 0.787234 (3712 -88);
FORCEPROP 1 LAST MATERIAL CHIP
J 0
(4025 -100);
DISPLAY 0.638298 (4025 -100);
FORCEPROP 1 LAST WATTAGE 1/16W
J 2
(3900 0);
DISPLAY 0.510638 (3900 0);
FORCEPROP 1 LAST TOLERANCE 1%
J 0
(3900 -100);
DISPLAY 0.638298 (3900 -100);
FORCEPROP 1 LAST VALUE 1K
J 2
(3850 -100);
DISPLAY 0.638298 (3850 -100);
FORCEPROP 1 LAST PACK_TYPE 0402LF
J 0
(3600 0);
DISPLAY 0.510638 (3600 0);
FORCEPROP 2 LAST CDS_LIB pure_quanta
J 0
(3650 -100);
PAINT MONO (3650 -100);
DISPLAY INVISIBLE (3650 -100);
FORCEPROP 1 LAST PATH I10
J 0
(3600 50);
DISPLAY 0.978723 (3600 50);
PAINT WHITE (3600 50);
DISPLAY INVISIBLE (3600 50);
FORCEPROP 1 LAST PART_NUMBER CS21002FB06
J 0
(3600 -50);
DISPLAY 0.510638 (3600 -50);
DISPLAY INVISIBLE (3600 -50);
FORCEADD UNIVERSAL_GND..1
(5300 175);
FORCEPROP 3 LASTPIN (5300 225) SIG_NAME GND\g
J 0
(5310 235);
DISPLAY 0.659574 (5310 235);
PAINT MONO (5310 235);
DISPLAY INVISIBLE (5310 235);
FORCEPROP 2 LAST CDS_LIB pure_quanta_power
J 0
(5300 175);
DISPLAY INVISIBLE (5300 175);
FORCEPROP 1 LAST HDL_POWER GND
J 1
(5325 100);
DISPLAY 0.872340 (5325 100);
PAINT GREEN (5325 100);
DISPLAY INVISIBLE (5325 100);
FORCEPROP 1 LAST PATH I100
J 0
(5375 175);
DISPLAY 0.872340 (5375 175);
PAINT AQUA (5375 175);
DISPLAY INVISIBLE (5375 175);
FORCEADD TAP..1
(5600 875);
FORCEPROP 3 LASTPIN (5550 875) SIG_NAME P5E_CPU1_G1_RX_DP<15>
J 0
(5560 885);
DISPLAY 0.659574 (5560 885);
PAINT MONO (5560 885);
DISPLAY INVISIBLE (5560 885);
FORCEPROP 1 LASTPIN (5550 875) BN 15
J 0
(5538 883);
DISPLAY 0.680851 (5538 883);
PAINT GREEN (5538 883);
FORCEPROP 2 LAST CDS_LIB standard
J 0
(5600 875);
PAINT MONO (5600 875);
DISPLAY INVISIBLE (5600 875);
FORCEPROP 1 LAST BODY_TYPE PLUMBING
J 0
(5600 925);
DISPLAY 0.872340 (5600 925);
PAINT GREEN (5600 925);
DISPLAY INVISIBLE (5600 925);
FORCEPROP 1 LAST HDL_TAP TRUE
J 0
(5925 750);
DISPLAY 0.872340 (5925 750);
PAINT GREEN (5925 750);
DISPLAY INVISIBLE (5925 750);
FORCEPROP 1 LAST PATH I101
J 0
(5598 875);
DISPLAY 0.872340 (5598 875);
PAINT GREEN (5598 875);
DISPLAY INVISIBLE (5598 875);
FORCEADD UNIVERSAL_POWER..1
(5700 50);
FORCEPROP 3 LASTPIN (5700 0) SIG_NAME P12V_OCP_V3_2_R\g
J 0
(5710 10);
DISPLAY 0.659574 (5710 10);
PAINT MONO (5710 10);
DISPLAY INVISIBLE (5710 10);
FORCEPROP 1 LAST HDL_POWER P12V_OCP_V3_2_R
J 1
(5700 100);
DISPLAY 0.872340 (5700 100);
PAINT GREEN (5700 100);
FORCEPROP 2 LAST CDS_LIB pure_quanta_power
J 0
(5700 50);
PAINT MONO (5700 50);
DISPLAY INVISIBLE (5700 50);
FORCEPROP 1 LAST PATH I102
J 0
(5750 75);
DISPLAY 0.872340 (5750 75);
PAINT AQUA (5750 75);
DISPLAY INVISIBLE (5750 75);
FORCEADD TAP..1
(5750 925);
FORCEPROP 3 LASTPIN (5700 925) SIG_NAME P5E_CPU1_G1_RX_DN<15>
J 0
(5710 935);
DISPLAY 0.659574 (5710 935);
PAINT MONO (5710 935);
DISPLAY INVISIBLE (5710 935);
FORCEPROP 1 LASTPIN (5700 925) BN 15
J 0
(5688 933);
DISPLAY 0.680851 (5688 933);
PAINT GREEN (5688 933);
FORCEPROP 2 LAST CDS_LIB standard
J 0
(5750 925);
PAINT MONO (5750 925);
DISPLAY INVISIBLE (5750 925);
FORCEPROP 1 LAST BODY_TYPE PLUMBING
J 0
(5750 975);
DISPLAY 0.872340 (5750 975);
PAINT GREEN (5750 975);
DISPLAY INVISIBLE (5750 975);
FORCEPROP 1 LAST HDL_TAP TRUE
J 0
(6075 800);
DISPLAY 0.872340 (6075 800);
PAINT GREEN (6075 800);
DISPLAY INVISIBLE (6075 800);
FORCEPROP 1 LAST PATH I103
J 0
(5748 925);
DISPLAY 0.872340 (5748 925);
PAINT GREEN (5748 925);
DISPLAY INVISIBLE (5748 925);
FORCEADD TAP..1
(5600 1025);
FORCEPROP 3 LASTPIN (5550 1025) SIG_NAME P5E_CPU1_G1_RX_DP<14>
J 0
(5560 1035);
DISPLAY 0.659574 (5560 1035);
PAINT MONO (5560 1035);
DISPLAY INVISIBLE (5560 1035);
FORCEPROP 1 LASTPIN (5550 1025) BN 14
J 0
(5538 1033);
DISPLAY 0.680851 (5538 1033);
PAINT GREEN (5538 1033);
FORCEPROP 2 LAST CDS_LIB standard
J 0
(5600 1025);
PAINT MONO (5600 1025);
DISPLAY INVISIBLE (5600 1025);
FORCEPROP 1 LAST BODY_TYPE PLUMBING
J 0
(5600 1075);
DISPLAY 0.872340 (5600 1075);
PAINT GREEN (5600 1075);
DISPLAY INVISIBLE (5600 1075);
FORCEPROP 1 LAST HDL_TAP TRUE
J 0
(5925 900);
DISPLAY 0.872340 (5925 900);
PAINT GREEN (5925 900);
DISPLAY INVISIBLE (5925 900);
FORCEPROP 1 LAST PATH I104
J 0
(5598 1025);
DISPLAY 0.872340 (5598 1025);
PAINT GREEN (5598 1025);
DISPLAY INVISIBLE (5598 1025);
FORCEADD TAP..1
(5600 1175);
FORCEPROP 3 LASTPIN (5550 1175) SIG_NAME P5E_CPU1_G1_RX_DP<13>
J 0
(5560 1185);
DISPLAY 0.659574 (5560 1185);
PAINT MONO (5560 1185);
DISPLAY INVISIBLE (5560 1185);
FORCEPROP 1 LASTPIN (5550 1175) BN 13
J 0
(5538 1183);
DISPLAY 0.680851 (5538 1183);
PAINT GREEN (5538 1183);
FORCEPROP 2 LAST CDS_LIB standard
J 0
(5600 1175);
PAINT MONO (5600 1175);
DISPLAY INVISIBLE (5600 1175);
FORCEPROP 1 LAST BODY_TYPE PLUMBING
J 0
(5600 1225);
DISPLAY 0.872340 (5600 1225);
PAINT GREEN (5600 1225);
DISPLAY INVISIBLE (5600 1225);
FORCEPROP 1 LAST HDL_TAP TRUE
J 0
(5925 1050);
DISPLAY 0.872340 (5925 1050);
PAINT GREEN (5925 1050);
DISPLAY INVISIBLE (5925 1050);
FORCEPROP 1 LAST PATH I105
J 0
(5598 1175);
DISPLAY 0.872340 (5598 1175);
PAINT GREEN (5598 1175);
DISPLAY INVISIBLE (5598 1175);
FORCEADD TAP..1
(5600 1475);
FORCEPROP 3 LASTPIN (5550 1475) SIG_NAME P5E_CPU1_G1_RX_DP<11>
J 0
(5560 1485);
DISPLAY 0.659574 (5560 1485);
PAINT MONO (5560 1485);
DISPLAY INVISIBLE (5560 1485);
FORCEPROP 1 LASTPIN (5550 1475) BN 11
J 0
(5538 1483);
DISPLAY 0.680851 (5538 1483);
PAINT GREEN (5538 1483);
FORCEPROP 2 LAST CDS_LIB standard
J 0
(5600 1475);
PAINT MONO (5600 1475);
DISPLAY INVISIBLE (5600 1475);
FORCEPROP 1 LAST BODY_TYPE PLUMBING
J 0
(5600 1525);
DISPLAY 0.872340 (5600 1525);
PAINT GREEN (5600 1525);
DISPLAY INVISIBLE (5600 1525);
FORCEPROP 1 LAST HDL_TAP TRUE
J 0
(5925 1350);
DISPLAY 0.872340 (5925 1350);
PAINT GREEN (5925 1350);
DISPLAY INVISIBLE (5925 1350);
FORCEPROP 1 LAST PATH I106
J 0
(5598 1475);
DISPLAY 0.872340 (5598 1475);
PAINT GREEN (5598 1475);
DISPLAY INVISIBLE (5598 1475);
FORCEADD TAP..1
(5600 1325);
FORCEPROP 3 LASTPIN (5550 1325) SIG_NAME P5E_CPU1_G1_RX_DP<12>
J 0
(5560 1335);
DISPLAY 0.659574 (5560 1335);
PAINT MONO (5560 1335);
DISPLAY INVISIBLE (5560 1335);
FORCEPROP 1 LASTPIN (5550 1325) BN 12
J 0
(5538 1333);
DISPLAY 0.680851 (5538 1333);
PAINT GREEN (5538 1333);
FORCEPROP 2 LAST CDS_LIB standard
J 0
(5600 1325);
PAINT MONO (5600 1325);
DISPLAY INVISIBLE (5600 1325);
FORCEPROP 1 LAST BODY_TYPE PLUMBING
J 0
(5600 1375);
DISPLAY 0.872340 (5600 1375);
PAINT GREEN (5600 1375);
DISPLAY INVISIBLE (5600 1375);
FORCEPROP 1 LAST HDL_TAP TRUE
J 0
(5925 1200);
DISPLAY 0.872340 (5925 1200);
PAINT GREEN (5925 1200);
DISPLAY INVISIBLE (5925 1200);
FORCEPROP 1 LAST PATH I107
J 0
(5598 1325);
DISPLAY 0.872340 (5598 1325);
PAINT GREEN (5598 1325);
DISPLAY INVISIBLE (5598 1325);
FORCEADD TAP..1
(5600 1625);
FORCEPROP 3 LASTPIN (5550 1625) SIG_NAME P5E_CPU1_G1_RX_DP<10>
J 0
(5560 1635);
DISPLAY 0.659574 (5560 1635);
PAINT MONO (5560 1635);
DISPLAY INVISIBLE (5560 1635);
FORCEPROP 1 LASTPIN (5550 1625) BN 10
J 0
(5538 1633);
DISPLAY 0.680851 (5538 1633);
PAINT GREEN (5538 1633);
FORCEPROP 2 LAST CDS_LIB standard
J 0
(5600 1625);
PAINT MONO (5600 1625);
DISPLAY INVISIBLE (5600 1625);
FORCEPROP 1 LAST BODY_TYPE PLUMBING
J 0
(5600 1675);
DISPLAY 0.872340 (5600 1675);
PAINT GREEN (5600 1675);
DISPLAY INVISIBLE (5600 1675);
FORCEPROP 1 LAST HDL_TAP TRUE
J 0
(5925 1500);
DISPLAY 0.872340 (5925 1500);
PAINT GREEN (5925 1500);
DISPLAY INVISIBLE (5925 1500);
FORCEPROP 1 LAST PATH I108
J 0
(5598 1625);
DISPLAY 0.872340 (5598 1625);
PAINT GREEN (5598 1625);
DISPLAY INVISIBLE (5598 1625);
FORCEADD TAP..1
(5600 1775);
FORCEPROP 3 LASTPIN (5550 1775) SIG_NAME P5E_CPU1_G1_RX_DP<9>
J 0
(5560 1785);
DISPLAY 0.659574 (5560 1785);
PAINT MONO (5560 1785);
DISPLAY INVISIBLE (5560 1785);
FORCEPROP 1 LASTPIN (5550 1775) BN 9
J 0
(5538 1783);
DISPLAY 0.680851 (5538 1783);
PAINT GREEN (5538 1783);
FORCEPROP 2 LAST CDS_LIB standard
J 0
(5600 1775);
PAINT MONO (5600 1775);
DISPLAY INVISIBLE (5600 1775);
FORCEPROP 1 LAST BODY_TYPE PLUMBING
J 0
(5600 1825);
DISPLAY 0.872340 (5600 1825);
PAINT GREEN (5600 1825);
DISPLAY INVISIBLE (5600 1825);
FORCEPROP 1 LAST HDL_TAP TRUE
J 0
(5925 1650);
DISPLAY 0.872340 (5925 1650);
PAINT GREEN (5925 1650);
DISPLAY INVISIBLE (5925 1650);
FORCEPROP 1 LAST PATH I109
J 0
(5598 1775);
DISPLAY 0.872340 (5598 1775);
PAINT GREEN (5598 1775);
DISPLAY INVISIBLE (5598 1775);
FORCEADD Q_RES..1
(3675 -625);
FORCEPROP 1 LAST LOCATION R3175
J 0
(3475 -625);
DISPLAY 0.638298 (3475 -625);
FORCEPROP 0 LAST $SEC 1
J 0
(3475 -575);
DISPLAY 0.680851 (3475 -575);
PAINT MONO (3475 -575);
DISPLAY INVISIBLE (3475 -575);
FORCEPROP 0 LAST CDS_SEC 1
J 0
(3475 -575);
DISPLAY 1.021277 (3475 -575);
DISPLAY INVISIBLE (3475 -575);
FORCEPROP 1 LASTPIN (3575 -625) $PN 1
J 0
(3587 -613);
DISPLAY 0.787234 (3587 -613);
PAINT MONO (3587 -613);
FORCEPROP 1 LASTPIN (3775 -625) $PN 2
J 0
(3737 -613);
DISPLAY 0.787234 (3737 -613);
PAINT MONO (3737 -613);
FORCEPROP 1 LAST TOLERANCE 1%
J 0
(3875 -625);
DISPLAY 0.510638 (3875 -625);
FORCEPROP 1 LAST VALUE 10K
J 2
(3850 -625);
DISPLAY 0.510638 (3850 -625);
FORCEPROP 1 LAST MATERIAL CHIP
J 0
(3950 -625);
DISPLAY 0.510638 (3950 -625);
FORCEPROP 1 LAST WATTAGE 1/16W
J 2
(3875 -500);
DISPLAY 0.510638 (3875 -500);
DISPLAY INVISIBLE (3875 -500);
FORCEPROP 1 LAST PACK_TYPE 0402LF
J 0
(3500 -500);
DISPLAY 0.510638 (3500 -500);
DISPLAY INVISIBLE (3500 -500);
FORCEPROP 2 LAST CDS_LIB pure_quanta
J 0
(3675 -625);
DISPLAY INVISIBLE (3675 -625);
FORCEPROP 1 LAST PATH I11
J 0
(3625 -475);
DISPLAY 0.978723 (3625 -475);
PAINT WHITE (3625 -475);
DISPLAY INVISIBLE (3625 -475);
FORCEPROP 1 LAST PART_NUMBER CS31002FB08
J 0
(3500 -550);
DISPLAY 0.510638 (3500 -550);
DISPLAY INVISIBLE (3500 -550);
FORCEADD TAP..1
(5600 1925);
FORCEPROP 3 LASTPIN (5550 1925) SIG_NAME P5E_CPU1_G1_RX_DP<8>
J 0
(5560 1935);
DISPLAY 0.659574 (5560 1935);
PAINT MONO (5560 1935);
DISPLAY INVISIBLE (5560 1935);
FORCEPROP 1 LASTPIN (5550 1925) BN 8
J 0
(5538 1933);
DISPLAY 0.680851 (5538 1933);
PAINT GREEN (5538 1933);
FORCEPROP 2 LAST CDS_LIB standard
J 0
(5600 1925);
PAINT MONO (5600 1925);
DISPLAY INVISIBLE (5600 1925);
FORCEPROP 1 LAST BODY_TYPE PLUMBING
J 0
(5600 1975);
DISPLAY 0.872340 (5600 1975);
PAINT GREEN (5600 1975);
DISPLAY INVISIBLE (5600 1975);
FORCEPROP 1 LAST HDL_TAP TRUE
J 0
(5925 1800);
DISPLAY 0.872340 (5925 1800);
PAINT GREEN (5925 1800);
DISPLAY INVISIBLE (5925 1800);
FORCEPROP 1 LAST PATH I110
J 0
(5598 1925);
DISPLAY 0.872340 (5598 1925);
PAINT GREEN (5598 1925);
DISPLAY INVISIBLE (5598 1925);
FORCEADD TAP..1
(5750 1225);
FORCEPROP 3 LASTPIN (5700 1225) SIG_NAME P5E_CPU1_G1_RX_DN<13>
J 0
(5710 1235);
DISPLAY 0.659574 (5710 1235);
PAINT MONO (5710 1235);
DISPLAY INVISIBLE (5710 1235);
FORCEPROP 1 LASTPIN (5700 1225) BN 13
J 0
(5688 1233);
DISPLAY 0.680851 (5688 1233);
PAINT GREEN (5688 1233);
FORCEPROP 2 LAST CDS_LIB standard
J 0
(5750 1225);
PAINT MONO (5750 1225);
DISPLAY INVISIBLE (5750 1225);
FORCEPROP 1 LAST BODY_TYPE PLUMBING
J 0
(5750 1275);
DISPLAY 0.872340 (5750 1275);
PAINT GREEN (5750 1275);
DISPLAY INVISIBLE (5750 1275);
FORCEPROP 1 LAST HDL_TAP TRUE
J 0
(6075 1100);
DISPLAY 0.872340 (6075 1100);
PAINT GREEN (6075 1100);
DISPLAY INVISIBLE (6075 1100);
FORCEPROP 1 LAST PATH I111
J 0
(5748 1225);
DISPLAY 0.872340 (5748 1225);
PAINT GREEN (5748 1225);
DISPLAY INVISIBLE (5748 1225);
FORCEADD TAP..1
(5750 1075);
FORCEPROP 3 LASTPIN (5700 1075) SIG_NAME P5E_CPU1_G1_RX_DN<14>
J 0
(5710 1085);
DISPLAY 0.659574 (5710 1085);
PAINT MONO (5710 1085);
DISPLAY INVISIBLE (5710 1085);
FORCEPROP 1 LASTPIN (5700 1075) BN 14
J 0
(5688 1083);
DISPLAY 0.680851 (5688 1083);
PAINT GREEN (5688 1083);
FORCEPROP 2 LAST CDS_LIB standard
J 0
(5750 1075);
PAINT MONO (5750 1075);
DISPLAY INVISIBLE (5750 1075);
FORCEPROP 1 LAST BODY_TYPE PLUMBING
J 0
(5750 1125);
DISPLAY 0.872340 (5750 1125);
PAINT GREEN (5750 1125);
DISPLAY INVISIBLE (5750 1125);
FORCEPROP 1 LAST HDL_TAP TRUE
J 0
(6075 950);
DISPLAY 0.872340 (6075 950);
PAINT GREEN (6075 950);
DISPLAY INVISIBLE (6075 950);
FORCEPROP 1 LAST PATH I112
J 0
(5748 1075);
DISPLAY 0.872340 (5748 1075);
PAINT GREEN (5748 1075);
DISPLAY INVISIBLE (5748 1075);
FORCEADD TAP..1
(5750 1375);
FORCEPROP 3 LASTPIN (5700 1375) SIG_NAME P5E_CPU1_G1_RX_DN<12>
J 0
(5710 1385);
DISPLAY 0.659574 (5710 1385);
PAINT MONO (5710 1385);
DISPLAY INVISIBLE (5710 1385);
FORCEPROP 1 LASTPIN (5700 1375) BN 12
J 0
(5688 1383);
DISPLAY 0.680851 (5688 1383);
PAINT GREEN (5688 1383);
FORCEPROP 2 LAST CDS_LIB standard
J 0
(5750 1375);
PAINT MONO (5750 1375);
DISPLAY INVISIBLE (5750 1375);
FORCEPROP 1 LAST BODY_TYPE PLUMBING
J 0
(5750 1425);
DISPLAY 0.872340 (5750 1425);
PAINT GREEN (5750 1425);
DISPLAY INVISIBLE (5750 1425);
FORCEPROP 1 LAST HDL_TAP TRUE
J 0
(6075 1250);
DISPLAY 0.872340 (6075 1250);
PAINT GREEN (6075 1250);
DISPLAY INVISIBLE (6075 1250);
FORCEPROP 1 LAST PATH I113
J 0
(5748 1375);
DISPLAY 0.872340 (5748 1375);
PAINT GREEN (5748 1375);
DISPLAY INVISIBLE (5748 1375);
FORCEADD TAP..1
(5750 1675);
FORCEPROP 3 LASTPIN (5700 1675) SIG_NAME P5E_CPU1_G1_RX_DN<10>
J 0
(5710 1685);
DISPLAY 0.659574 (5710 1685);
PAINT MONO (5710 1685);
DISPLAY INVISIBLE (5710 1685);
FORCEPROP 1 LASTPIN (5700 1675) BN 10
J 0
(5688 1683);
DISPLAY 0.680851 (5688 1683);
PAINT GREEN (5688 1683);
FORCEPROP 2 LAST CDS_LIB standard
J 0
(5750 1675);
PAINT MONO (5750 1675);
DISPLAY INVISIBLE (5750 1675);
FORCEPROP 1 LAST BODY_TYPE PLUMBING
J 0
(5750 1725);
DISPLAY 0.872340 (5750 1725);
PAINT GREEN (5750 1725);
DISPLAY INVISIBLE (5750 1725);
FORCEPROP 1 LAST HDL_TAP TRUE
J 0
(6075 1550);
DISPLAY 0.872340 (6075 1550);
PAINT GREEN (6075 1550);
DISPLAY INVISIBLE (6075 1550);
FORCEPROP 1 LAST PATH I114
J 0
(5748 1675);
DISPLAY 0.872340 (5748 1675);
PAINT GREEN (5748 1675);
DISPLAY INVISIBLE (5748 1675);
FORCEADD TAP..1
(5750 1525);
FORCEPROP 3 LASTPIN (5700 1525) SIG_NAME P5E_CPU1_G1_RX_DN<11>
J 0
(5710 1535);
DISPLAY 0.659574 (5710 1535);
PAINT MONO (5710 1535);
DISPLAY INVISIBLE (5710 1535);
FORCEPROP 1 LASTPIN (5700 1525) BN 11
J 0
(5688 1533);
DISPLAY 0.680851 (5688 1533);
PAINT GREEN (5688 1533);
FORCEPROP 2 LAST CDS_LIB standard
J 0
(5750 1525);
PAINT MONO (5750 1525);
DISPLAY INVISIBLE (5750 1525);
FORCEPROP 1 LAST BODY_TYPE PLUMBING
J 0
(5750 1575);
DISPLAY 0.872340 (5750 1575);
PAINT GREEN (5750 1575);
DISPLAY INVISIBLE (5750 1575);
FORCEPROP 1 LAST HDL_TAP TRUE
J 0
(6075 1400);
DISPLAY 0.872340 (6075 1400);
PAINT GREEN (6075 1400);
DISPLAY INVISIBLE (6075 1400);
FORCEPROP 1 LAST PATH I115
J 0
(5748 1525);
DISPLAY 0.872340 (5748 1525);
PAINT GREEN (5748 1525);
DISPLAY INVISIBLE (5748 1525);
FORCEADD TAP..1
(5750 1975);
FORCEPROP 3 LASTPIN (5700 1975) SIG_NAME P5E_CPU1_G1_RX_DN<8>
J 0
(5710 1985);
DISPLAY 0.659574 (5710 1985);
PAINT MONO (5710 1985);
DISPLAY INVISIBLE (5710 1985);
FORCEPROP 1 LASTPIN (5700 1975) BN 8
J 0
(5688 1983);
DISPLAY 0.680851 (5688 1983);
PAINT GREEN (5688 1983);
FORCEPROP 2 LAST CDS_LIB standard
J 0
(5750 1975);
PAINT MONO (5750 1975);
DISPLAY INVISIBLE (5750 1975);
FORCEPROP 1 LAST BODY_TYPE PLUMBING
J 0
(5750 2025);
DISPLAY 0.872340 (5750 2025);
PAINT GREEN (5750 2025);
DISPLAY INVISIBLE (5750 2025);
FORCEPROP 1 LAST HDL_TAP TRUE
J 0
(6075 1850);
DISPLAY 0.872340 (6075 1850);
PAINT GREEN (6075 1850);
DISPLAY INVISIBLE (6075 1850);
FORCEPROP 1 LAST PATH I116
J 0
(5748 1975);
DISPLAY 0.872340 (5748 1975);
PAINT GREEN (5748 1975);
DISPLAY INVISIBLE (5748 1975);
FORCEADD TAP..1
(5750 1825);
FORCEPROP 3 LASTPIN (5700 1825) SIG_NAME P5E_CPU1_G1_RX_DN<9>
J 0
(5710 1835);
DISPLAY 0.659574 (5710 1835);
PAINT MONO (5710 1835);
DISPLAY INVISIBLE (5710 1835);
FORCEPROP 1 LASTPIN (5700 1825) BN 9
J 0
(5688 1833);
DISPLAY 0.680851 (5688 1833);
PAINT GREEN (5688 1833);
FORCEPROP 2 LAST CDS_LIB standard
J 0
(5750 1825);
PAINT MONO (5750 1825);
DISPLAY INVISIBLE (5750 1825);
FORCEPROP 1 LAST BODY_TYPE PLUMBING
J 0
(5750 1875);
DISPLAY 0.872340 (5750 1875);
PAINT GREEN (5750 1875);
DISPLAY INVISIBLE (5750 1875);
FORCEPROP 1 LAST HDL_TAP TRUE
J 0
(6075 1700);
DISPLAY 0.872340 (6075 1700);
PAINT GREEN (6075 1700);
DISPLAY INVISIBLE (6075 1700);
FORCEPROP 1 LAST PATH I117
J 0
(5748 1825);
DISPLAY 0.872340 (5748 1825);
PAINT GREEN (5748 1825);
DISPLAY INVISIBLE (5748 1825);
FORCEADD TAP..1
(5600 2275);
FORCEPROP 3 LASTPIN (5550 2275) SIG_NAME P5E_CPU1_G1_RX_DP<7>
J 0
(5560 2285);
DISPLAY 0.659574 (5560 2285);
PAINT MONO (5560 2285);
DISPLAY INVISIBLE (5560 2285);
FORCEPROP 1 LASTPIN (5550 2275) BN 7
J 0
(5538 2283);
DISPLAY 0.680851 (5538 2283);
PAINT GREEN (5538 2283);
FORCEPROP 2 LAST CDS_LIB standard
J 0
(5600 2275);
PAINT MONO (5600 2275);
DISPLAY INVISIBLE (5600 2275);
FORCEPROP 1 LAST BODY_TYPE PLUMBING
J 0
(5600 2325);
DISPLAY 0.872340 (5600 2325);
PAINT GREEN (5600 2325);
DISPLAY INVISIBLE (5600 2325);
FORCEPROP 1 LAST HDL_TAP TRUE
J 0
(5925 2150);
DISPLAY 0.872340 (5925 2150);
PAINT GREEN (5925 2150);
DISPLAY INVISIBLE (5925 2150);
FORCEPROP 1 LAST PATH I118
J 0
(5598 2275);
DISPLAY 0.872340 (5598 2275);
PAINT GREEN (5598 2275);
DISPLAY INVISIBLE (5598 2275);
FORCEADD TAP..1
(5600 2425);
FORCEPROP 3 LASTPIN (5550 2425) SIG_NAME P5E_CPU1_G1_RX_DP<6>
J 0
(5560 2435);
DISPLAY 0.659574 (5560 2435);
PAINT MONO (5560 2435);
DISPLAY INVISIBLE (5560 2435);
FORCEPROP 1 LASTPIN (5550 2425) BN 6
J 0
(5538 2433);
DISPLAY 0.680851 (5538 2433);
PAINT GREEN (5538 2433);
FORCEPROP 2 LAST CDS_LIB standard
J 0
(5600 2425);
PAINT MONO (5600 2425);
DISPLAY INVISIBLE (5600 2425);
FORCEPROP 1 LAST BODY_TYPE PLUMBING
J 0
(5600 2475);
DISPLAY 0.872340 (5600 2475);
PAINT GREEN (5600 2475);
DISPLAY INVISIBLE (5600 2475);
FORCEPROP 1 LAST HDL_TAP TRUE
J 0
(5925 2300);
DISPLAY 0.872340 (5925 2300);
PAINT GREEN (5925 2300);
DISPLAY INVISIBLE (5925 2300);
FORCEPROP 1 LAST PATH I119
J 0
(5598 2425);
DISPLAY 0.872340 (5598 2425);
PAINT GREEN (5598 2425);
DISPLAY INVISIBLE (5598 2425);
FORCEADD Q_RES..1
(3675 -450);
FORCEPROP 1 LAST LOCATION R3176
J 0
(3475 -450);
DISPLAY 0.638298 (3475 -450);
FORCEPROP 0 LAST $SEC 1
J 0
(3925 -325);
DISPLAY 0.680851 (3925 -325);
PAINT MONO (3925 -325);
DISPLAY INVISIBLE (3925 -325);
FORCEPROP 0 LAST CDS_SEC 1
J 0
(3925 -325);
DISPLAY 1.021277 (3925 -325);
DISPLAY INVISIBLE (3925 -325);
FORCEPROP 1 LASTPIN (3575 -450) $PN 1
J 0
(3587 -438);
DISPLAY 0.787234 (3587 -438);
PAINT MONO (3587 -438);
FORCEPROP 1 LASTPIN (3775 -450) $PN 2
J 0
(3737 -438);
DISPLAY 0.787234 (3737 -438);
PAINT MONO (3737 -438);
FORCEPROP 1 LAST PACK_TYPE 0402LF
J 0
(3625 -350);
DISPLAY 0.510638 (3625 -350);
FORCEPROP 1 LAST TOLERANCE 1%
J 0
(3925 -450);
DISPLAY 0.638298 (3925 -450);
FORCEPROP 1 LAST VALUE 1K
J 2
(3875 -450);
DISPLAY 0.638298 (3875 -450);
FORCEPROP 1 LAST WATTAGE 1/16W
J 2
(3925 -350);
DISPLAY 0.510638 (3925 -350);
FORCEPROP 1 LAST MATERIAL CHIP
J 0
(4050 -450);
DISPLAY 0.638298 (4050 -450);
FORCEPROP 2 LAST CDS_LIB pure_quanta
J 0
(3675 -450);
DISPLAY INVISIBLE (3675 -450);
FORCEPROP 1 LAST PATH I12
J 0
(3625 -300);
DISPLAY 0.978723 (3625 -300);
PAINT WHITE (3625 -300);
DISPLAY INVISIBLE (3625 -300);
FORCEPROP 1 LAST PART_NUMBER CS21002FB06
J 0
(3625 -400);
DISPLAY 0.510638 (3625 -400);
DISPLAY INVISIBLE (3625 -400);
FORCEADD TAP..1
(5600 2725);
FORCEPROP 3 LASTPIN (5550 2725) SIG_NAME P5E_CPU1_G1_RX_DP<4>
J 0
(5560 2735);
DISPLAY 0.659574 (5560 2735);
PAINT MONO (5560 2735);
DISPLAY INVISIBLE (5560 2735);
FORCEPROP 1 LASTPIN (5550 2725) BN 4
J 0
(5538 2733);
DISPLAY 0.680851 (5538 2733);
PAINT GREEN (5538 2733);
FORCEPROP 2 LAST CDS_LIB standard
J 0
(5600 2725);
PAINT MONO (5600 2725);
DISPLAY INVISIBLE (5600 2725);
FORCEPROP 1 LAST BODY_TYPE PLUMBING
J 0
(5600 2775);
DISPLAY 0.872340 (5600 2775);
PAINT GREEN (5600 2775);
DISPLAY INVISIBLE (5600 2775);
FORCEPROP 1 LAST HDL_TAP TRUE
J 0
(5925 2600);
DISPLAY 0.872340 (5925 2600);
PAINT GREEN (5925 2600);
DISPLAY INVISIBLE (5925 2600);
FORCEPROP 1 LAST PATH I120
J 0
(5598 2725);
DISPLAY 0.872340 (5598 2725);
PAINT GREEN (5598 2725);
DISPLAY INVISIBLE (5598 2725);
FORCEADD TAP..1
(5600 2575);
FORCEPROP 3 LASTPIN (5550 2575) SIG_NAME P5E_CPU1_G1_RX_DP<5>
J 0
(5560 2585);
DISPLAY 0.659574 (5560 2585);
PAINT MONO (5560 2585);
DISPLAY INVISIBLE (5560 2585);
FORCEPROP 1 LASTPIN (5550 2575) BN 5
J 0
(5538 2583);
DISPLAY 0.680851 (5538 2583);
PAINT GREEN (5538 2583);
FORCEPROP 2 LAST CDS_LIB standard
J 0
(5600 2575);
PAINT MONO (5600 2575);
DISPLAY INVISIBLE (5600 2575);
FORCEPROP 1 LAST BODY_TYPE PLUMBING
J 0
(5600 2625);
DISPLAY 0.872340 (5600 2625);
PAINT GREEN (5600 2625);
DISPLAY INVISIBLE (5600 2625);
FORCEPROP 1 LAST HDL_TAP TRUE
J 0
(5925 2450);
DISPLAY 0.872340 (5925 2450);
PAINT GREEN (5925 2450);
DISPLAY INVISIBLE (5925 2450);
FORCEPROP 1 LAST PATH I121
J 0
(5598 2575);
DISPLAY 0.872340 (5598 2575);
PAINT GREEN (5598 2575);
DISPLAY INVISIBLE (5598 2575);
FORCEADD TAP..1
(5750 2475);
FORCEPROP 3 LASTPIN (5700 2475) SIG_NAME P5E_CPU1_G1_RX_DN<6>
J 0
(5710 2485);
DISPLAY 0.659574 (5710 2485);
PAINT MONO (5710 2485);
DISPLAY INVISIBLE (5710 2485);
FORCEPROP 1 LASTPIN (5700 2475) BN 6
J 0
(5688 2483);
DISPLAY 0.680851 (5688 2483);
PAINT GREEN (5688 2483);
FORCEPROP 2 LAST CDS_LIB standard
J 0
(5750 2475);
PAINT MONO (5750 2475);
DISPLAY INVISIBLE (5750 2475);
FORCEPROP 1 LAST BODY_TYPE PLUMBING
J 0
(5750 2525);
DISPLAY 0.872340 (5750 2525);
PAINT GREEN (5750 2525);
DISPLAY INVISIBLE (5750 2525);
FORCEPROP 1 LAST HDL_TAP TRUE
J 0
(6075 2350);
DISPLAY 0.872340 (6075 2350);
PAINT GREEN (6075 2350);
DISPLAY INVISIBLE (6075 2350);
FORCEPROP 1 LAST PATH I122
J 0
(5748 2475);
DISPLAY 0.872340 (5748 2475);
PAINT GREEN (5748 2475);
DISPLAY INVISIBLE (5748 2475);
FORCEADD TAP..1
(5750 2325);
FORCEPROP 3 LASTPIN (5700 2325) SIG_NAME P5E_CPU1_G1_RX_DN<7>
J 0
(5710 2335);
DISPLAY 0.659574 (5710 2335);
PAINT MONO (5710 2335);
DISPLAY INVISIBLE (5710 2335);
FORCEPROP 1 LASTPIN (5700 2325) BN 7
J 0
(5688 2333);
DISPLAY 0.680851 (5688 2333);
PAINT GREEN (5688 2333);
FORCEPROP 2 LAST CDS_LIB standard
J 0
(5750 2325);
PAINT MONO (5750 2325);
DISPLAY INVISIBLE (5750 2325);
FORCEPROP 1 LAST BODY_TYPE PLUMBING
J 0
(5750 2375);
DISPLAY 0.872340 (5750 2375);
PAINT GREEN (5750 2375);
DISPLAY INVISIBLE (5750 2375);
FORCEPROP 1 LAST HDL_TAP TRUE
J 0
(6075 2200);
DISPLAY 0.872340 (6075 2200);
PAINT GREEN (6075 2200);
DISPLAY INVISIBLE (6075 2200);
FORCEPROP 1 LAST PATH I123
J 0
(5748 2325);
DISPLAY 0.872340 (5748 2325);
PAINT GREEN (5748 2325);
DISPLAY INVISIBLE (5748 2325);
FORCEADD TAP..1
(5750 2625);
FORCEPROP 3 LASTPIN (5700 2625) SIG_NAME P5E_CPU1_G1_RX_DN<5>
J 0
(5710 2635);
DISPLAY 0.659574 (5710 2635);
PAINT MONO (5710 2635);
DISPLAY INVISIBLE (5710 2635);
FORCEPROP 1 LASTPIN (5700 2625) BN 5
J 0
(5688 2633);
DISPLAY 0.680851 (5688 2633);
PAINT GREEN (5688 2633);
FORCEPROP 2 LAST CDS_LIB standard
J 0
(5750 2625);
PAINT MONO (5750 2625);
DISPLAY INVISIBLE (5750 2625);
FORCEPROP 1 LAST BODY_TYPE PLUMBING
J 0
(5750 2675);
DISPLAY 0.872340 (5750 2675);
PAINT GREEN (5750 2675);
DISPLAY INVISIBLE (5750 2675);
FORCEPROP 1 LAST HDL_TAP TRUE
J 0
(6075 2500);
DISPLAY 0.872340 (6075 2500);
PAINT GREEN (6075 2500);
DISPLAY INVISIBLE (6075 2500);
FORCEPROP 1 LAST PATH I124
J 0
(5748 2625);
DISPLAY 0.872340 (5748 2625);
PAINT GREEN (5748 2625);
DISPLAY INVISIBLE (5748 2625);
FORCEADD TAP..1
(5750 2775);
FORCEPROP 3 LASTPIN (5700 2775) SIG_NAME P5E_CPU1_G1_RX_DN<4>
J 0
(5710 2785);
DISPLAY 0.659574 (5710 2785);
PAINT MONO (5710 2785);
DISPLAY INVISIBLE (5710 2785);
FORCEPROP 1 LASTPIN (5700 2775) BN 4
J 0
(5688 2783);
DISPLAY 0.680851 (5688 2783);
PAINT GREEN (5688 2783);
FORCEPROP 2 LAST CDS_LIB standard
J 0
(5750 2775);
PAINT MONO (5750 2775);
DISPLAY INVISIBLE (5750 2775);
FORCEPROP 1 LAST BODY_TYPE PLUMBING
J 0
(5750 2825);
DISPLAY 0.872340 (5750 2825);
PAINT GREEN (5750 2825);
DISPLAY INVISIBLE (5750 2825);
FORCEPROP 1 LAST HDL_TAP TRUE
J 0
(6075 2650);
DISPLAY 0.872340 (6075 2650);
PAINT GREEN (6075 2650);
DISPLAY INVISIBLE (6075 2650);
FORCEPROP 1 LAST PATH I125
J 0
(5748 2775);
DISPLAY 0.872340 (5748 2775);
PAINT GREEN (5748 2775);
DISPLAY INVISIBLE (5748 2775);
FORCEADD TAP..1
(5600 3025);
FORCEPROP 3 LASTPIN (5550 3025) SIG_NAME P5E_CPU1_G1_RX_DP<3>
J 0
(5560 3035);
DISPLAY 0.659574 (5560 3035);
PAINT MONO (5560 3035);
DISPLAY INVISIBLE (5560 3035);
FORCEPROP 1 LASTPIN (5550 3025) BN 3
J 0
(5538 3033);
DISPLAY 0.680851 (5538 3033);
PAINT GREEN (5538 3033);
FORCEPROP 2 LAST CDS_LIB standard
J 0
(5600 3025);
PAINT MONO (5600 3025);
DISPLAY INVISIBLE (5600 3025);
FORCEPROP 1 LAST BODY_TYPE PLUMBING
J 0
(5600 3075);
DISPLAY 0.872340 (5600 3075);
PAINT GREEN (5600 3075);
DISPLAY INVISIBLE (5600 3075);
FORCEPROP 1 LAST HDL_TAP TRUE
J 0
(5925 2900);
DISPLAY 0.872340 (5925 2900);
PAINT GREEN (5925 2900);
DISPLAY INVISIBLE (5925 2900);
FORCEPROP 1 LAST PATH I126
J 0
(5598 3025);
DISPLAY 0.872340 (5598 3025);
PAINT GREEN (5598 3025);
DISPLAY INVISIBLE (5598 3025);
FORCEADD TAP..1
(5600 3175);
FORCEPROP 3 LASTPIN (5550 3175) SIG_NAME P5E_CPU1_G1_RX_DP<2>
J 0
(5560 3185);
DISPLAY 0.659574 (5560 3185);
PAINT MONO (5560 3185);
DISPLAY INVISIBLE (5560 3185);
FORCEPROP 1 LASTPIN (5550 3175) BN 2
J 0
(5538 3183);
DISPLAY 0.680851 (5538 3183);
PAINT GREEN (5538 3183);
FORCEPROP 2 LAST CDS_LIB standard
J 0
(5600 3175);
PAINT MONO (5600 3175);
DISPLAY INVISIBLE (5600 3175);
FORCEPROP 1 LAST BODY_TYPE PLUMBING
J 0
(5600 3225);
DISPLAY 0.872340 (5600 3225);
PAINT GREEN (5600 3225);
DISPLAY INVISIBLE (5600 3225);
FORCEPROP 1 LAST HDL_TAP TRUE
J 0
(5925 3050);
DISPLAY 0.872340 (5925 3050);
PAINT GREEN (5925 3050);
DISPLAY INVISIBLE (5925 3050);
FORCEPROP 1 LAST PATH I127
J 0
(5598 3175);
DISPLAY 0.872340 (5598 3175);
PAINT GREEN (5598 3175);
DISPLAY INVISIBLE (5598 3175);
FORCEADD TAP..1
(5600 3325);
FORCEPROP 3 LASTPIN (5550 3325) SIG_NAME P5E_CPU1_G1_RX_DP<1>
J 0
(5560 3335);
DISPLAY 0.659574 (5560 3335);
PAINT MONO (5560 3335);
DISPLAY INVISIBLE (5560 3335);
FORCEPROP 1 LASTPIN (5550 3325) BN 1
J 0
(5538 3333);
DISPLAY 0.680851 (5538 3333);
PAINT GREEN (5538 3333);
FORCEPROP 2 LAST CDS_LIB standard
J 0
(5600 3325);
PAINT MONO (5600 3325);
DISPLAY INVISIBLE (5600 3325);
FORCEPROP 1 LAST BODY_TYPE PLUMBING
J 0
(5600 3375);
DISPLAY 0.872340 (5600 3375);
PAINT GREEN (5600 3375);
DISPLAY INVISIBLE (5600 3375);
FORCEPROP 1 LAST HDL_TAP TRUE
J 0
(5925 3200);
DISPLAY 0.872340 (5925 3200);
PAINT GREEN (5925 3200);
DISPLAY INVISIBLE (5925 3200);
FORCEPROP 1 LAST PATH I128
J 0
(5598 3325);
DISPLAY 0.872340 (5598 3325);
PAINT GREEN (5598 3325);
DISPLAY INVISIBLE (5598 3325);
FORCEADD TAP..1
(5600 3475);
FORCEPROP 3 LASTPIN (5550 3475) SIG_NAME P5E_CPU1_G1_RX_DP<0>
J 0
(5560 3485);
DISPLAY 0.659574 (5560 3485);
PAINT MONO (5560 3485);
DISPLAY INVISIBLE (5560 3485);
FORCEPROP 1 LASTPIN (5550 3475) BN 0
J 0
(5538 3483);
DISPLAY 0.680851 (5538 3483);
PAINT GREEN (5538 3483);
FORCEPROP 2 LAST CDS_LIB standard
J 0
(5600 3475);
PAINT MONO (5600 3475);
DISPLAY INVISIBLE (5600 3475);
FORCEPROP 1 LAST BODY_TYPE PLUMBING
J 0
(5600 3525);
DISPLAY 0.872340 (5600 3525);
PAINT GREEN (5600 3525);
DISPLAY INVISIBLE (5600 3525);
FORCEPROP 1 LAST HDL_TAP TRUE
J 0
(5925 3350);
DISPLAY 0.872340 (5925 3350);
PAINT GREEN (5925 3350);
DISPLAY INVISIBLE (5925 3350);
FORCEPROP 1 LAST PATH I129
J 0
(5598 3475);
DISPLAY 0.872340 (5598 3475);
PAINT GREEN (5598 3475);
DISPLAY INVISIBLE (5598 3475);
FORCEADD Q_CAP..1
(5700 -300);
FORCEPROP 1 LAST LOCATION C1829
J 0
(5750 -200);
DISPLAY 0.787234 (5750 -200);
FORCEPROP 2 LAST $SEC 1
J 0
(5750 -100);
DISPLAY 0.680851 (5750 -100);
PAINT MONO (5750 -100);
DISPLAY INVISIBLE (5750 -100);
FORCEPROP 2 LAST CDS_SEC 1
J 0
(5750 -100);
DISPLAY 1.021277 (5750 -100);
DISPLAY INVISIBLE (5750 -100);
FORCEPROP 1 LASTPIN (5700 -200) $PN 1
J 0
(5710 -220);
DISPLAY 0.787234 (5710 -220);
FORCEPROP 1 LASTPIN (5700 -400) $PN 2
J 0
(5710 -420);
DISPLAY 0.787234 (5710 -420);
FORCEPROP 1 LAST VALUE 22UF
J 0
(5750 -250);
DISPLAY 0.638298 (5750 -250);
FORCEPROP 1 LAST MATERIAL X6S
J 0
(5750 -400);
DISPLAY 0.638298 (5750 -400);
FORCEPROP 1 LAST TOLERANCE 20%
J 0
(5750 -350);
DISPLAY 0.638298 (5750 -350);
FORCEPROP 1 LAST VOLTAGE 16V
J 0
(5750 -300);
DISPLAY 0.638298 (5750 -300);
FORCEPROP 1 LAST PACK_TYPE C0805
J 0
(5750 -450);
DISPLAY 0.638298 (5750 -450);
FORCEPROP 2 LAST CDS_LIB pure_quanta
J 0
(5700 -300);
PAINT MONO (5700 -300);
DISPLAY INVISIBLE (5700 -300);
FORCEPROP 1 LAST PATH I13
J 0
(5750 -150);
DISPLAY 0.978723 (5750 -150);
PAINT WHITE (5750 -150);
DISPLAY INVISIBLE (5750 -150);
FORCEPROP 1 LAST PART_NUMBER CH6223MEA00
J 0
(5750 -500);
DISPLAY 0.808511 (5750 -500);
DISPLAY INVISIBLE (5750 -500);
FORCEADD TAP..1
(5750 3225);
FORCEPROP 3 LASTPIN (5700 3225) SIG_NAME P5E_CPU1_G1_RX_DN<2>
J 0
(5710 3235);
DISPLAY 0.659574 (5710 3235);
PAINT MONO (5710 3235);
DISPLAY INVISIBLE (5710 3235);
FORCEPROP 1 LASTPIN (5700 3225) BN 2
J 0
(5688 3233);
DISPLAY 0.680851 (5688 3233);
PAINT GREEN (5688 3233);
FORCEPROP 2 LAST CDS_LIB standard
J 0
(5750 3225);
PAINT MONO (5750 3225);
DISPLAY INVISIBLE (5750 3225);
FORCEPROP 1 LAST BODY_TYPE PLUMBING
J 0
(5750 3275);
DISPLAY 0.872340 (5750 3275);
PAINT GREEN (5750 3275);
DISPLAY INVISIBLE (5750 3275);
FORCEPROP 1 LAST HDL_TAP TRUE
J 0
(6075 3100);
DISPLAY 0.872340 (6075 3100);
PAINT GREEN (6075 3100);
DISPLAY INVISIBLE (6075 3100);
FORCEPROP 1 LAST PATH I130
J 0
(5748 3225);
DISPLAY 0.872340 (5748 3225);
PAINT GREEN (5748 3225);
DISPLAY INVISIBLE (5748 3225);
FORCEADD TAP..1
(5750 3075);
FORCEPROP 3 LASTPIN (5700 3075) SIG_NAME P5E_CPU1_G1_RX_DN<3>
J 0
(5710 3085);
DISPLAY 0.659574 (5710 3085);
PAINT MONO (5710 3085);
DISPLAY INVISIBLE (5710 3085);
FORCEPROP 1 LASTPIN (5700 3075) BN 3
J 0
(5688 3083);
DISPLAY 0.680851 (5688 3083);
PAINT GREEN (5688 3083);
FORCEPROP 2 LAST CDS_LIB standard
J 0
(5750 3075);
PAINT MONO (5750 3075);
DISPLAY INVISIBLE (5750 3075);
FORCEPROP 1 LAST BODY_TYPE PLUMBING
J 0
(5750 3125);
DISPLAY 0.872340 (5750 3125);
PAINT GREEN (5750 3125);
DISPLAY INVISIBLE (5750 3125);
FORCEPROP 1 LAST HDL_TAP TRUE
J 0
(6075 2950);
DISPLAY 0.872340 (6075 2950);
PAINT GREEN (6075 2950);
DISPLAY INVISIBLE (6075 2950);
FORCEPROP 1 LAST PATH I131
J 0
(5748 3075);
DISPLAY 0.872340 (5748 3075);
PAINT GREEN (5748 3075);
DISPLAY INVISIBLE (5748 3075);
FORCEADD TAP..1
(5750 3525);
FORCEPROP 3 LASTPIN (5700 3525) SIG_NAME P5E_CPU1_G1_RX_DN<0>
J 0
(5710 3535);
DISPLAY 0.659574 (5710 3535);
PAINT MONO (5710 3535);
DISPLAY INVISIBLE (5710 3535);
FORCEPROP 1 LASTPIN (5700 3525) BN 0
J 0
(5688 3533);
DISPLAY 0.680851 (5688 3533);
PAINT GREEN (5688 3533);
FORCEPROP 2 LAST CDS_LIB standard
J 0
(5750 3525);
PAINT MONO (5750 3525);
DISPLAY INVISIBLE (5750 3525);
FORCEPROP 1 LAST BODY_TYPE PLUMBING
J 0
(5750 3575);
DISPLAY 0.872340 (5750 3575);
PAINT GREEN (5750 3575);
DISPLAY INVISIBLE (5750 3575);
FORCEPROP 1 LAST HDL_TAP TRUE
J 0
(6075 3400);
DISPLAY 0.872340 (6075 3400);
DISPLAY INVISIBLE (6075 3400);
FORCEPROP 1 LAST PATH I132
J 0
(5748 3525);
DISPLAY 0.872340 (5748 3525);
PAINT GREEN (5748 3525);
DISPLAY INVISIBLE (5748 3525);
FORCEADD TAP..1
(5750 3375);
FORCEPROP 3 LASTPIN (5700 3375) SIG_NAME P5E_CPU1_G1_RX_DN<1>
J 0
(5710 3385);
DISPLAY 0.659574 (5710 3385);
PAINT MONO (5710 3385);
DISPLAY INVISIBLE (5710 3385);
FORCEPROP 1 LASTPIN (5700 3375) BN 1
J 0
(5688 3383);
DISPLAY 0.680851 (5688 3383);
PAINT GREEN (5688 3383);
FORCEPROP 2 LAST CDS_LIB standard
J 0
(5750 3375);
PAINT MONO (5750 3375);
DISPLAY INVISIBLE (5750 3375);
FORCEPROP 1 LAST BODY_TYPE PLUMBING
J 0
(5750 3425);
DISPLAY 0.872340 (5750 3425);
PAINT GREEN (5750 3425);
DISPLAY INVISIBLE (5750 3425);
FORCEPROP 1 LAST HDL_TAP TRUE
J 0
(6075 3250);
DISPLAY 0.872340 (6075 3250);
PAINT GREEN (6075 3250);
DISPLAY INVISIBLE (6075 3250);
FORCEPROP 1 LAST PATH I133
J 0
(5748 3375);
DISPLAY 0.872340 (5748 3375);
PAINT GREEN (5748 3375);
DISPLAY INVISIBLE (5748 3375);
FORCEADD OFFPAGE..4
(6425 675);
FORCEPROP 2 LAST $XR0 139 
J 0
(6611 675);
DISPLAY 0.638298 (6611 675);
PAINT MONO (6611 675);
FORCEPROP 2 LAST CDS_LIB standard
J 0
(6425 675);
PAINT MONO (6425 675);
DISPLAY INVISIBLE (6425 675);
FORCEPROP 1 LAST OFFPAGE TRUE
J 0
(6750 550);
DISPLAY 0.872340 (6750 550);
PAINT GREEN (6750 550);
DISPLAY INVISIBLE (6750 550);
FORCEPROP 1 LAST COMMENT_BODY TRUE
J 0
(6400 575);
DISPLAY 0.872340 (6400 575);
PAINT GREEN (6400 575);
DISPLAY INVISIBLE (6400 575);
FORCEPROP 2 LAST PATH I134
J 0
(6625 725);
DISPLAY 0.680851 (6625 725);
DISPLAY INVISIBLE (6625 725);
FORCEADD Q_RES..1
(6850 725);
FORCEPROP 1 LAST LOCATION R3178
J 0
(6575 725);
DISPLAY 0.638298 (6575 725);
FORCEPROP 2 LAST $SEC 1
J 0
(6800 925);
DISPLAY 0.680851 (6800 925);
PAINT MONO (6800 925);
DISPLAY INVISIBLE (6800 925);
FORCEPROP 2 LAST CDS_SEC 1
J 0
(6800 925);
DISPLAY 1.021277 (6800 925);
DISPLAY INVISIBLE (6800 925);
FORCEPROP 1 LASTPIN (6750 725) $PN 1
J 0
(6762 737);
DISPLAY 0.787234 (6762 737);
FORCEPROP 1 LASTPIN (6950 725) $PN 2
J 0
(6912 737);
DISPLAY 0.787234 (6912 737);
FORCEPROP 1 LAST PACK_TYPE 0402LF
J 0
(7125 725);
DISPLAY 0.638298 (7125 725);
FORCEPROP 1 LAST VALUE 0
J 2
(7025 725);
DISPLAY 0.638298 (7025 725);
FORCEPROP 1 LAST TOLERANCE 5%
J 0
(7050 725);
DISPLAY 0.638298 (7050 725);
FORCEPROP 2 LAST CDS_LIB pure_quanta
J 0
(6850 725);
PAINT MONO (6850 725);
DISPLAY INVISIBLE (6850 725);
FORCEPROP 1 LAST WATTAGE 1/16W
J 2
(7025 850);
DISPLAY 0.638298 (7025 850);
DISPLAY INVISIBLE (7025 850);
FORCEPROP 1 LAST MATERIAL CHIP
J 0
(6725 850);
DISPLAY 0.638298 (6725 850);
DISPLAY INVISIBLE (6725 850);
FORCEPROP 1 LAST PATH I135
J 0
(6800 875);
DISPLAY 0.978723 (6800 875);
PAINT WHITE (6800 875);
DISPLAY INVISIBLE (6800 875);
FORCEPROP 1 LAST PART_NUMBER CS00002JB13
J 0
(6725 800);
DISPLAY 0.638298 (6725 800);
DISPLAY INVISIBLE (6725 800);
FORCEADD Q_RES..1
(6850 775);
FORCEPROP 1 LAST LOCATION R3177
J 0
(6575 775);
DISPLAY 0.638298 (6575 775);
FORCEPROP 2 LAST $SEC 1
J 0
(6800 975);
DISPLAY 0.680851 (6800 975);
PAINT MONO (6800 975);
DISPLAY INVISIBLE (6800 975);
FORCEPROP 2 LAST CDS_SEC 1
J 0
(6800 975);
DISPLAY 1.021277 (6800 975);
DISPLAY INVISIBLE (6800 975);
FORCEPROP 1 LASTPIN (6750 775) $PN 1
J 0
(6762 787);
DISPLAY 0.787234 (6762 787);
FORCEPROP 1 LASTPIN (6950 775) $PN 2
J 0
(6912 787);
DISPLAY 0.787234 (6912 787);
FORCEPROP 1 LAST VALUE 0
J 2
(7025 775);
DISPLAY 0.638298 (7025 775);
FORCEPROP 1 LAST PACK_TYPE 0402LF
J 0
(7125 775);
DISPLAY 0.638298 (7125 775);
FORCEPROP 1 LAST TOLERANCE 5%
J 0
(7050 775);
DISPLAY 0.638298 (7050 775);
FORCEPROP 1 LAST WATTAGE 1/16W
J 2
(7025 900);
DISPLAY 0.638298 (7025 900);
FORCEPROP 1 LAST MATERIAL CHIP
J 0
(6725 900);
DISPLAY 0.638298 (6725 900);
FORCEPROP 2 LAST CDS_LIB pure_quanta
J 0
(6850 775);
PAINT MONO (6850 775);
DISPLAY INVISIBLE (6850 775);
FORCEPROP 1 LAST PATH I136
J 0
(6800 925);
DISPLAY 0.978723 (6800 925);
PAINT WHITE (6800 925);
DISPLAY INVISIBLE (6800 925);
FORCEPROP 1 LAST PART_NUMBER CS00002JB13
J 0
(6725 850);
DISPLAY 0.638298 (6725 850);
DISPLAY INVISIBLE (6725 850);
FORCEADD UNIVERSAL_POWER..1
(7900 50);
FORCEPROP 3 LASTPIN (7900 0) SIG_NAME P3V3_OCP_V3_2\g
J 0
(7910 10);
DISPLAY 0.659574 (7910 10);
PAINT MONO (7910 10);
DISPLAY INVISIBLE (7910 10);
FORCEPROP 1 LAST HDL_POWER P3V3_OCP_V3_2
J 1
(7900 100);
DISPLAY 0.872340 (7900 100);
PAINT GREEN (7900 100);
FORCEPROP 2 LAST CDS_LIB pure_quanta_power
J 0
(7900 50);
PAINT MONO (7900 50);
DISPLAY INVISIBLE (7900 50);
FORCEPROP 1 LAST PATH I137
J 0
(7950 75);
DISPLAY 0.872340 (7950 75);
PAINT AQUA (7950 75);
DISPLAY INVISIBLE (7950 75);
FORCEADD OFFPAGE..2
(6750 2175);
FORCEPROP 2 LAST $XR1 143 
J 0
(7059 2175);
DISPLAY 0.638298 (7059 2175);
PAINT MONO (7059 2175);
FORCEPROP 2 LAST $XR0 140 
J 0
(6939 2175);
DISPLAY 0.638298 (6939 2175);
PAINT MONO (6939 2175);
FORCEPROP 2 LAST CDS_LIB standard
J 0
(6750 2175);
DISPLAY INVISIBLE (6750 2175);
FORCEPROP 1 LAST OFFPAGE TRUE
J 0
(7075 2050);
DISPLAY 0.872340 (7075 2050);
PAINT GREEN (7075 2050);
DISPLAY INVISIBLE (7075 2050);
FORCEPROP 1 LAST COMMENT_BODY TRUE
J 0
(6705 2080);
DISPLAY 0.872340 (6705 2080);
PAINT GREEN (6705 2080);
DISPLAY INVISIBLE (6705 2080);
FORCEPROP 2 LAST PATH I138
J 0
(7075 2225);
DISPLAY 0.680851 (7075 2225);
DISPLAY INVISIBLE (7075 2225);
FORCEADD Q_CAP..1
(5975 -300);
FORCEPROP 1 LAST LOCATION C1830
J 0
(6025 -200);
DISPLAY 0.787234 (6025 -200);
FORCEPROP 2 LAST $SEC 1
J 0
(6025 -100);
DISPLAY 0.680851 (6025 -100);
PAINT MONO (6025 -100);
DISPLAY INVISIBLE (6025 -100);
FORCEPROP 2 LAST CDS_SEC 1
J 0
(6025 -100);
DISPLAY 1.021277 (6025 -100);
DISPLAY INVISIBLE (6025 -100);
FORCEPROP 1 LASTPIN (5975 -200) $PN 1
J 0
(5985 -220);
DISPLAY 0.787234 (5985 -220);
FORCEPROP 1 LASTPIN (5975 -400) $PN 2
J 0
(5985 -420);
DISPLAY 0.787234 (5985 -420);
FORCEPROP 1 LAST PACK_TYPE C0805
J 0
(6025 -500);
DISPLAY 0.638298 (6025 -500);
FORCEPROP 1 LAST MATERIAL X6S
J 0
(6025 -400);
DISPLAY 0.638298 (6025 -400);
FORCEPROP 1 LAST TOLERANCE 20%
J 0
(6025 -350);
DISPLAY 0.638298 (6025 -350);
FORCEPROP 1 LAST VOLTAGE 16V
J 0
(6025 -300);
DISPLAY 0.638298 (6025 -300);
FORCEPROP 1 LAST VALUE 22UF
J 0
(6025 -250);
DISPLAY 0.638298 (6025 -250);
FORCEPROP 2 LAST CDS_LIB pure_quanta
J 0
(5975 -300);
PAINT MONO (5975 -300);
DISPLAY INVISIBLE (5975 -300);
FORCEPROP 1 LAST PATH I14
J 0
(6025 -150);
DISPLAY 0.978723 (6025 -150);
PAINT WHITE (6025 -150);
DISPLAY INVISIBLE (6025 -150);
FORCEPROP 1 LAST PART_NUMBER CH6223MEA00
J 0
(6025 -450);
DISPLAY 0.638298 (6025 -450);
DISPLAY INVISIBLE (6025 -450);
FORCEADD OFFPAGE..2
(6800 3500);
FORCEPROP 2 LAST $XR0 49 
J 0
(6989 3500);
DISPLAY 0.638298 (6989 3500);
PAINT MONO (6989 3500);
FORCEPROP 2 LAST CDS_LIB standard
J 0
(6800 3500);
DISPLAY INVISIBLE (6800 3500);
FORCEPROP 1 LAST OFFPAGE TRUE
J 0
(7125 3375);
DISPLAY 0.872340 (7125 3375);
PAINT GREEN (7125 3375);
DISPLAY INVISIBLE (7125 3375);
FORCEPROP 1 LAST COMMENT_BODY TRUE
J 0
(6755 3405);
DISPLAY 0.872340 (6755 3405);
PAINT GREEN (6755 3405);
DISPLAY INVISIBLE (6755 3405);
FORCEPROP 2 LAST PATH I141
J 0
(7000 3550);
DISPLAY 0.680851 (7000 3550);
DISPLAY INVISIBLE (7000 3550);
FORCEADD OFFPAGE..2
(6800 3550);
FORCEPROP 2 LAST $XR0 49 
J 0
(6989 3550);
DISPLAY 0.638298 (6989 3550);
PAINT MONO (6989 3550);
FORCEPROP 2 LAST CDS_LIB standard
J 0
(6800 3550);
DISPLAY INVISIBLE (6800 3550);
FORCEPROP 1 LAST OFFPAGE TRUE
J 0
(7125 3425);
DISPLAY 0.872340 (7125 3425);
PAINT GREEN (7125 3425);
DISPLAY INVISIBLE (7125 3425);
FORCEPROP 1 LAST COMMENT_BODY TRUE
J 0
(6755 3455);
DISPLAY 0.872340 (6755 3455);
PAINT GREEN (6755 3455);
DISPLAY INVISIBLE (6755 3455);
FORCEPROP 2 LAST PATH I142
J 0
(7000 3600);
DISPLAY 0.680851 (7000 3600);
DISPLAY INVISIBLE (7000 3600);
FORCEADD OFFPAGE..1
R 2
(6775 3625);
FORCEPROP 2 LAST $XR0 55 
J 0
(6961 3625);
DISPLAY 0.638298 (6961 3625);
PAINT MONO (6961 3625);
FORCEPROP 2 LAST CDS_LIB standard
J 2
(6775 3625);
DISPLAY INVISIBLE (6775 3625);
FORCEPROP 1 LAST OFFPAGE TRUE
J 2
(6450 3500);
DISPLAY 0.872340 (6450 3500);
PAINT GREEN (6450 3500);
DISPLAY INVISIBLE (6450 3500);
FORCEPROP 1 LAST COMMENT_BODY TRUE
J 2
(6650 3525);
DISPLAY 0.872340 (6650 3525);
PAINT GREEN (6650 3525);
DISPLAY INVISIBLE (6650 3525);
FORCEPROP 2 LAST PATH I143
J 0
(6975 3675);
DISPLAY 0.680851 (6975 3675);
DISPLAY INVISIBLE (6975 3675);
FORCEADD OFFPAGE..1
R 2
(6775 3675);
FORCEPROP 2 LAST $XR0 55 
J 0
(6961 3675);
DISPLAY 0.638298 (6961 3675);
PAINT MONO (6961 3675);
FORCEPROP 2 LAST CDS_LIB standard
J 2
(6775 3675);
DISPLAY INVISIBLE (6775 3675);
FORCEPROP 1 LAST OFFPAGE TRUE
J 2
(6450 3550);
DISPLAY 0.872340 (6450 3550);
PAINT GREEN (6450 3550);
DISPLAY INVISIBLE (6450 3550);
FORCEPROP 1 LAST COMMENT_BODY TRUE
J 2
(6650 3575);
DISPLAY 0.872340 (6650 3575);
PAINT GREEN (6650 3575);
DISPLAY INVISIBLE (6650 3575);
FORCEPROP 2 LAST PATH I144
J 0
(6975 3725);
DISPLAY 0.680851 (6975 3725);
DISPLAY INVISIBLE (6975 3725);
FORCEADD OFFPAGE..2
(6775 3775);
FORCEPROP 2 LAST $XR0 140 
J 0
(6964 3775);
DISPLAY 0.638298 (6964 3775);
PAINT MONO (6964 3775);
FORCEPROP 2 LAST $XR1 143 
J 0
(7084 3775);
DISPLAY 0.638298 (7084 3775);
PAINT MONO (7084 3775);
FORCEPROP 2 LAST CDS_LIB standard
J 0
(6775 3775);
DISPLAY INVISIBLE (6775 3775);
FORCEPROP 1 LAST OFFPAGE TRUE
J 0
(7100 3650);
DISPLAY 0.872340 (7100 3650);
PAINT GREEN (7100 3650);
DISPLAY INVISIBLE (7100 3650);
FORCEPROP 1 LAST COMMENT_BODY TRUE
J 0
(6730 3680);
DISPLAY 0.872340 (6730 3680);
PAINT GREEN (6730 3680);
DISPLAY INVISIBLE (6730 3680);
FORCEPROP 2 LAST PATH I145
J 0
(7100 3825);
DISPLAY 0.680851 (7100 3825);
DISPLAY INVISIBLE (7100 3825);
FORCEADD OFFPAGE..4
(6775 3825);
FORCEPROP 2 LAST $XR0 139 
J 0
(6961 3825);
DISPLAY 0.638298 (6961 3825);
PAINT MONO (6961 3825);
FORCEPROP 2 LAST CDS_LIB standard
J 0
(6775 3825);
PAINT MONO (6775 3825);
DISPLAY INVISIBLE (6775 3825);
FORCEPROP 1 LAST OFFPAGE TRUE
J 0
(7100 3700);
DISPLAY 0.872340 (7100 3700);
PAINT GREEN (7100 3700);
DISPLAY INVISIBLE (7100 3700);
FORCEPROP 1 LAST COMMENT_BODY TRUE
J 0
(6750 3725);
DISPLAY 0.872340 (6750 3725);
PAINT GREEN (6750 3725);
DISPLAY INVISIBLE (6750 3725);
FORCEPROP 2 LAST PATH I146
J 0
(6975 3875);
DISPLAY 0.680851 (6975 3875);
DISPLAY INVISIBLE (6975 3875);
FORCEADD OFFPAGE..4
(7675 3925);
FORCEPROP 2 LAST $XR0 139 
J 0
(7891 3925);
DISPLAY 0.638298 (7891 3925);
PAINT MONO (7891 3925);
FORCEPROP 2 LAST CDS_LIB standard
J 0
(7675 3925);
DISPLAY INVISIBLE (7675 3925);
FORCEPROP 1 LAST OFFPAGE TRUE
J 0
(8000 3800);
DISPLAY 0.872340 (8000 3800);
PAINT GREEN (8000 3800);
DISPLAY INVISIBLE (8000 3800);
FORCEPROP 1 LAST COMMENT_BODY TRUE
J 0
(7650 3825);
DISPLAY 0.872340 (7650 3825);
PAINT GREEN (7650 3825);
DISPLAY INVISIBLE (7650 3825);
FORCEPROP 2 LAST PATH I147
J 0
(7900 3975);
DISPLAY 0.680851 (7900 3975);
DISPLAY INVISIBLE (7900 3975);
FORCEADD OFFPAGE..4
(7675 4025);
FORCEPROP 2 LAST $XR0 248 
J 0
(7861 4025);
DISPLAY 0.638298 (7861 4025);
PAINT MONO (7861 4025);
FORCEPROP 2 LAST CDS_LIB standard
J 0
(7675 4025);
PAINT MONO (7675 4025);
DISPLAY INVISIBLE (7675 4025);
FORCEPROP 1 LAST OFFPAGE TRUE
J 0
(8000 3900);
DISPLAY 0.872340 (8000 3900);
PAINT GREEN (8000 3900);
DISPLAY INVISIBLE (8000 3900);
FORCEPROP 1 LAST COMMENT_BODY TRUE
J 0
(7650 3925);
DISPLAY 0.872340 (7650 3925);
PAINT GREEN (7650 3925);
DISPLAY INVISIBLE (7650 3925);
FORCEPROP 2 LAST PATH I148
J 0
(7875 4075);
DISPLAY 0.680851 (7875 4075);
DISPLAY INVISIBLE (7875 4075);
FORCEADD OFFPAGE..3
(7675 3975);
FORCEPROP 2 LAST $XR0 248 
J 0
(7889 3975);
DISPLAY 0.638298 (7889 3975);
PAINT MONO (7889 3975);
FORCEPROP 2 LAST CDS_LIB standard
J 0
(7675 3975);
PAINT MONO (7675 3975);
DISPLAY INVISIBLE (7675 3975);
FORCEPROP 1 LAST OFFPAGE TRUE
J 0
(8000 3850);
DISPLAY 0.872340 (8000 3850);
DISPLAY INVISIBLE (8000 3850);
FORCEPROP 1 LAST COMMENT_BODY TRUE
J 0
(7625 3875);
DISPLAY 0.872340 (7625 3875);
PAINT GREEN (7625 3875);
DISPLAY INVISIBLE (7625 3875);
FORCEPROP 2 LAST PATH I149
J 0
(7900 4025);
DISPLAY 0.680851 (7900 4025);
DISPLAY INVISIBLE (7900 4025);
FORCEADD Q_CAP..1
(6375 -300);
FORCEPROP 1 LAST LOCATION C1831
J 0
(6425 -200);
DISPLAY 0.787234 (6425 -200);
FORCEPROP 2 LAST $SEC 1
J 0
(6425 -100);
DISPLAY 0.680851 (6425 -100);
PAINT MONO (6425 -100);
DISPLAY INVISIBLE (6425 -100);
FORCEPROP 2 LAST CDS_SEC 1
J 0
(6425 -100);
DISPLAY 1.021277 (6425 -100);
DISPLAY INVISIBLE (6425 -100);
FORCEPROP 1 LASTPIN (6375 -200) $PN 1
J 0
(6385 -220);
DISPLAY 0.787234 (6385 -220);
FORCEPROP 1 LASTPIN (6375 -400) $PN 2
J 0
(6385 -420);
DISPLAY 0.787234 (6385 -420);
FORCEPROP 1 LAST PACK_TYPE 0402
J 0
(6425 -450);
DISPLAY 0.638298 (6425 -450);
FORCEPROP 1 LAST VOLTAGE 25V
J 0
(6425 -300);
DISPLAY 0.638298 (6425 -300);
FORCEPROP 1 LAST MATERIAL X7R
J 0
(6425 -400);
DISPLAY 0.638298 (6425 -400);
FORCEPROP 1 LAST TOLERANCE 10%
J 0
(6425 -350);
DISPLAY 0.638298 (6425 -350);
FORCEPROP 1 LAST VALUE 0.1UF
J 0
(6425 -250);
DISPLAY 0.638298 (6425 -250);
FORCEPROP 2 LAST CDS_LIB pure_quanta
J 0
(6375 -300);
PAINT MONO (6375 -300);
DISPLAY INVISIBLE (6375 -300);
FORCEPROP 1 LAST PATH I15
J 0
(6425 -150);
DISPLAY 0.978723 (6425 -150);
PAINT WHITE (6425 -150);
DISPLAY INVISIBLE (6425 -150);
FORCEPROP 1 LAST PART_NUMBER CH4104K1B00
J 0
(6425 -450);
DISPLAY 0.808511 (6425 -450);
DISPLAY INVISIBLE (6425 -450);
FORCEADD Q_RES..2
(7950 3625);
FORCEPROP 1 LAST LOCATION R3180
J 0
(7995 3750);
DISPLAY 0.638298 (7995 3750);
FORCEPROP 0 LAST $SEC 1
J 0
(8000 3800);
DISPLAY 0.680851 (8000 3800);
PAINT MONO (8000 3800);
DISPLAY INVISIBLE (8000 3800);
FORCEPROP 0 LAST CDS_SEC 1
J 0
(8000 3800);
DISPLAY 1.021277 (8000 3800);
DISPLAY INVISIBLE (8000 3800);
FORCEPROP 1 LASTPIN (7950 3725) $PN 1
J 0
(7955 3687);
DISPLAY 0.787234 (7955 3687);
PAINT MONO (7955 3687);
FORCEPROP 1 LASTPIN (7950 3525) $PN 2
J 0
(7955 3535);
DISPLAY 0.787234 (7955 3535);
PAINT MONO (7955 3535);
FORCEPROP 1 LAST PACK_TYPE 0402LF
J 0
(7990 3450);
DISPLAY 0.638298 (7990 3450);
FORCEPROP 1 LAST WATTAGE 1/16W
J 0
(7990 3600);
DISPLAY 0.638298 (7990 3600);
FORCEPROP 1 LAST MATERIAL CHIP
J 0
(7990 3550);
DISPLAY 0.638298 (7990 3550);
FORCEPROP 1 LAST VALUE 0
J 0
(7995 3700);
DISPLAY 0.638298 (7995 3700);
FORCEPROP 1 LAST TOLERANCE 5%
J 0
(7995 3650);
DISPLAY 0.638298 (7995 3650);
FORCEPROP 2 LAST CDS_LIB pure_quanta
J 0
(7950 3625);
DISPLAY INVISIBLE (7950 3625);
FORCEPROP 1 LAST PATH I150
J 0
(8000 3800);
DISPLAY 0.978723 (8000 3800);
PAINT WHITE (8000 3800);
DISPLAY INVISIBLE (8000 3800);
FORCEPROP 1 LAST PART_NUMBER CS00002JB13
J 0
(7990 3500);
DISPLAY 0.638298 (7990 3500);
DISPLAY INVISIBLE (7990 3500);
FORCEADD UNIVERSAL_GND..1
(7950 3350);
FORCEPROP 3 LASTPIN (7950 3400) SIG_NAME GND\g
J 0
(7960 3410);
DISPLAY 0.659574 (7960 3410);
PAINT MONO (7960 3410);
DISPLAY INVISIBLE (7960 3410);
FORCEPROP 2 LAST ROOM IO_SLOT
J 1
(7725 3425);
DISPLAY 0.744681 (7725 3425);
FORCEPROP 2 LAST CDS_LIB pure_quanta_power
J 0
(7950 3350);
DISPLAY INVISIBLE (7950 3350);
FORCEPROP 1 LAST HDL_POWER GND
J 1
(7975 3275);
DISPLAY 0.872340 (7975 3275);
PAINT GREEN (7975 3275);
DISPLAY INVISIBLE (7975 3275);
FORCEPROP 1 LAST PATH I151
J 0
(8025 3350);
DISPLAY 0.872340 (8025 3350);
PAINT AQUA (8025 3350);
DISPLAY INVISIBLE (8025 3350);
FORCEADD OFFPAGE..4
(6250 4475);
FORCEPROP 2 LAST $XR0 139 
J 0
(6436 4475);
DISPLAY 0.638298 (6436 4475);
PAINT MONO (6436 4475);
FORCEPROP 2 LAST CDS_LIB standard
J 0
(6250 4475);
PAINT MONO (6250 4475);
DISPLAY INVISIBLE (6250 4475);
FORCEPROP 1 LAST OFFPAGE TRUE
J 0
(6575 4350);
DISPLAY 0.872340 (6575 4350);
PAINT GREEN (6575 4350);
DISPLAY INVISIBLE (6575 4350);
FORCEPROP 1 LAST COMMENT_BODY TRUE
J 0
(6225 4375);
DISPLAY 0.872340 (6225 4375);
PAINT GREEN (6225 4375);
DISPLAY INVISIBLE (6225 4375);
FORCEPROP 2 LAST PATH I152
J 0
(6450 4525);
DISPLAY 0.680851 (6450 4525);
DISPLAY INVISIBLE (6450 4525);
FORCEADD OFFPAGE..1
R 2
(6250 4575);
FORCEPROP 2 LAST $XR0 55 
J 0
(6436 4575);
DISPLAY 0.638298 (6436 4575);
PAINT MONO (6436 4575);
FORCEPROP 2 LAST CDS_LIB standard
J 0
(6250 4575);
DISPLAY INVISIBLE (6250 4575);
FORCEPROP 1 LAST OFFPAGE TRUE
J 2
(5925 4450);
DISPLAY 0.872340 (5925 4450);
PAINT GREEN (5925 4450);
DISPLAY INVISIBLE (5925 4450);
FORCEPROP 1 LAST COMMENT_BODY TRUE
J 2
(6125 4475);
DISPLAY 0.872340 (6125 4475);
PAINT GREEN (6125 4475);
DISPLAY INVISIBLE (6125 4475);
FORCEPROP 2 LAST PATH I153
J 0
(6450 4625);
DISPLAY 0.680851 (6450 4625);
DISPLAY INVISIBLE (6450 4625);
FORCEADD OFFPAGE..1
R 2
(6250 4625);
FORCEPROP 2 LAST $XR0 55 
J 0
(6436 4625);
DISPLAY 0.638298 (6436 4625);
PAINT MONO (6436 4625);
FORCEPROP 2 LAST CDS_LIB standard
J 0
(6250 4625);
DISPLAY INVISIBLE (6250 4625);
FORCEPROP 1 LAST OFFPAGE TRUE
J 2
(5925 4500);
DISPLAY 0.872340 (5925 4500);
PAINT GREEN (5925 4500);
DISPLAY INVISIBLE (5925 4500);
FORCEPROP 1 LAST COMMENT_BODY TRUE
J 2
(6125 4525);
DISPLAY 0.872340 (6125 4525);
PAINT GREEN (6125 4525);
DISPLAY INVISIBLE (6125 4525);
FORCEPROP 2 LAST PATH I154
J 0
(6450 4675);
DISPLAY 0.680851 (6450 4675);
DISPLAY INVISIBLE (6450 4675);
FORCEADD OFFPAGE..4
(6250 4725);
FORCEPROP 2 LAST $XR0 138 
J 0
(6436 4725);
DISPLAY 0.638298 (6436 4725);
PAINT MONO (6436 4725);
FORCEPROP 2 LAST CDS_LIB standard
J 0
(6250 4725);
PAINT MONO (6250 4725);
DISPLAY INVISIBLE (6250 4725);
FORCEPROP 1 LAST OFFPAGE TRUE
J 0
(6575 4600);
DISPLAY 0.872340 (6575 4600);
PAINT GREEN (6575 4600);
DISPLAY INVISIBLE (6575 4600);
FORCEPROP 1 LAST COMMENT_BODY TRUE
J 0
(6225 4625);
DISPLAY 0.872340 (6225 4625);
PAINT GREEN (6225 4625);
DISPLAY INVISIBLE (6225 4625);
FORCEPROP 2 LAST PATH I155
J 0
(6450 4775);
DISPLAY 0.680851 (6450 4775);
DISPLAY INVISIBLE (6450 4775);
FORCEADD OFFPAGE..4
(6250 4775);
FORCEPROP 2 LAST $XR0 138 
J 0
(6436 4775);
DISPLAY 0.638298 (6436 4775);
PAINT MONO (6436 4775);
FORCEPROP 2 LAST CDS_LIB standard
J 0
(6250 4775);
PAINT MONO (6250 4775);
DISPLAY INVISIBLE (6250 4775);
FORCEPROP 1 LAST OFFPAGE TRUE
J 0
(6575 4650);
DISPLAY 0.872340 (6575 4650);
PAINT GREEN (6575 4650);
DISPLAY INVISIBLE (6575 4650);
FORCEPROP 1 LAST COMMENT_BODY TRUE
J 0
(6225 4675);
DISPLAY 0.872340 (6225 4675);
PAINT GREEN (6225 4675);
DISPLAY INVISIBLE (6225 4675);
FORCEPROP 2 LAST PATH I156
J 0
(6450 4825);
DISPLAY 0.680851 (6450 4825);
DISPLAY INVISIBLE (6450 4825);
FORCEADD OFFPAGE..4
(6250 4825);
FORCEPROP 2 LAST $XR0 138 
J 0
(6436 4825);
DISPLAY 0.638298 (6436 4825);
PAINT MONO (6436 4825);
FORCEPROP 2 LAST CDS_LIB standard
J 0
(6250 4825);
PAINT MONO (6250 4825);
DISPLAY INVISIBLE (6250 4825);
FORCEPROP 1 LAST OFFPAGE TRUE
J 0
(6575 4700);
DISPLAY 0.872340 (6575 4700);
PAINT GREEN (6575 4700);
DISPLAY INVISIBLE (6575 4700);
FORCEPROP 1 LAST COMMENT_BODY TRUE
J 0
(6225 4725);
DISPLAY 0.872340 (6225 4725);
PAINT GREEN (6225 4725);
DISPLAY INVISIBLE (6225 4725);
FORCEPROP 2 LAST PATH I157
J 0
(6450 4875);
DISPLAY 0.680851 (6450 4875);
DISPLAY INVISIBLE (6450 4875);
FORCEADD OFFPAGE..4
(6250 4875);
FORCEPROP 2 LAST $XR0 137 
J 0
(6436 4875);
DISPLAY 0.638298 (6436 4875);
PAINT MONO (6436 4875);
FORCEPROP 2 LAST CDS_LIB standard
J 0
(6250 4875);
PAINT MONO (6250 4875);
DISPLAY INVISIBLE (6250 4875);
FORCEPROP 1 LAST OFFPAGE TRUE
J 0
(6575 4750);
DISPLAY 0.872340 (6575 4750);
PAINT GREEN (6575 4750);
DISPLAY INVISIBLE (6575 4750);
FORCEPROP 1 LAST COMMENT_BODY TRUE
J 0
(6225 4775);
DISPLAY 0.872340 (6225 4775);
PAINT GREEN (6225 4775);
DISPLAY INVISIBLE (6225 4775);
FORCEPROP 2 LAST PATH I158
J 0
(6450 4925);
DISPLAY 0.680851 (6450 4925);
DISPLAY INVISIBLE (6450 4925);
FORCEADD OFFPAGE..4
(6250 4925);
FORCEPROP 2 LAST $XR0 138 
J 0
(6436 4925);
DISPLAY 0.638298 (6436 4925);
PAINT MONO (6436 4925);
FORCEPROP 2 LAST CDS_LIB standard
J 0
(6250 4925);
DISPLAY INVISIBLE (6250 4925);
FORCEPROP 1 LAST OFFPAGE TRUE
J 0
(6575 4800);
DISPLAY 0.872340 (6575 4800);
PAINT GREEN (6575 4800);
DISPLAY INVISIBLE (6575 4800);
FORCEPROP 1 LAST COMMENT_BODY TRUE
J 0
(6225 4825);
DISPLAY 0.872340 (6225 4825);
PAINT GREEN (6225 4825);
DISPLAY INVISIBLE (6225 4825);
FORCEPROP 2 LAST PATH I159
J 0
(6450 4975);
DISPLAY 0.680851 (6450 4975);
DISPLAY INVISIBLE (6450 4975);
FORCEADD Q_CAP..1
(6650 -300);
FORCEPROP 1 LAST LOCATION C1832
J 0
(6700 -200);
DISPLAY 0.787234 (6700 -200);
FORCEPROP 2 LAST $SEC 1
J 0
(6700 -100);
DISPLAY 0.680851 (6700 -100);
PAINT MONO (6700 -100);
DISPLAY INVISIBLE (6700 -100);
FORCEPROP 2 LAST CDS_SEC 1
J 0
(6700 -100);
DISPLAY 1.021277 (6700 -100);
DISPLAY INVISIBLE (6700 -100);
FORCEPROP 1 LASTPIN (6650 -200) $PN 1
J 0
(6660 -220);
DISPLAY 0.787234 (6660 -220);
FORCEPROP 1 LASTPIN (6650 -400) $PN 2
J 0
(6660 -420);
DISPLAY 0.787234 (6660 -420);
FORCEPROP 1 LAST VALUE 0.1UF
J 0
(6700 -250);
DISPLAY 0.638298 (6700 -250);
FORCEPROP 1 LAST MATERIAL X7R
J 0
(6700 -400);
DISPLAY 0.638298 (6700 -400);
FORCEPROP 1 LAST PACK_TYPE 0402
J 0
(6700 -450);
DISPLAY 0.638298 (6700 -450);
FORCEPROP 1 LAST VOLTAGE 25V
J 0
(6700 -300);
DISPLAY 0.638298 (6700 -300);
FORCEPROP 1 LAST TOLERANCE 10%
J 0
(6700 -350);
DISPLAY 0.638298 (6700 -350);
FORCEPROP 2 LAST CDS_LIB pure_quanta
J 0
(6650 -300);
PAINT MONO (6650 -300);
DISPLAY INVISIBLE (6650 -300);
FORCEPROP 1 LAST PATH I16
J 0
(6700 -150);
DISPLAY 0.978723 (6700 -150);
PAINT WHITE (6700 -150);
DISPLAY INVISIBLE (6700 -150);
FORCEPROP 1 LAST PART_NUMBER CH4104K1B00
J 0
(6700 -450);
DISPLAY 0.808511 (6700 -450);
DISPLAY INVISIBLE (6700 -450);
FORCEADD OFFPAGE..2
(6250 5025);
FORCEPROP 2 LAST $XR0 139 
J 0
(6439 5025);
DISPLAY 0.638298 (6439 5025);
PAINT MONO (6439 5025);
FORCEPROP 2 LAST CDS_LIB standard
J 0
(6250 5025);
PAINT MONO (6250 5025);
DISPLAY INVISIBLE (6250 5025);
FORCEPROP 1 LAST OFFPAGE TRUE
J 0
(6575 4900);
DISPLAY 0.872340 (6575 4900);
PAINT GREEN (6575 4900);
DISPLAY INVISIBLE (6575 4900);
FORCEPROP 1 LAST COMMENT_BODY TRUE
J 0
(6205 4930);
DISPLAY 0.872340 (6205 4930);
PAINT GREEN (6205 4930);
DISPLAY INVISIBLE (6205 4930);
FORCEPROP 2 LAST PATH I160
J 0
(6450 5075);
DISPLAY 0.680851 (6450 5075);
DISPLAY INVISIBLE (6450 5075);
FORCEADD OFFPAGE..2
(6250 4975);
FORCEPROP 2 LAST $XR0 138 
J 0
(6439 4975);
DISPLAY 0.638298 (6439 4975);
PAINT MONO (6439 4975);
FORCEPROP 2 LAST CDS_LIB standard
J 0
(6250 4975);
DISPLAY INVISIBLE (6250 4975);
FORCEPROP 1 LAST OFFPAGE TRUE
J 0
(6575 4850);
DISPLAY 0.872340 (6575 4850);
PAINT GREEN (6575 4850);
DISPLAY INVISIBLE (6575 4850);
FORCEPROP 1 LAST COMMENT_BODY TRUE
J 0
(6205 4880);
DISPLAY 0.872340 (6205 4880);
PAINT GREEN (6205 4880);
DISPLAY INVISIBLE (6205 4880);
FORCEPROP 2 LAST PATH I161
J 0
(6450 5025);
DISPLAY 0.680851 (6450 5025);
DISPLAY INVISIBLE (6450 5025);
FORCEADD OFFPAGE..4
(6250 5075);
FORCEPROP 2 LAST $XR0 139 
J 0
(6436 5075);
DISPLAY 0.638298 (6436 5075);
PAINT MONO (6436 5075);
FORCEPROP 2 LAST CDS_LIB standard
J 0
(6250 5075);
PAINT MONO (6250 5075);
DISPLAY INVISIBLE (6250 5075);
FORCEPROP 1 LAST OFFPAGE TRUE
J 0
(6575 4950);
DISPLAY 0.872340 (6575 4950);
PAINT GREEN (6575 4950);
DISPLAY INVISIBLE (6575 4950);
FORCEPROP 1 LAST COMMENT_BODY TRUE
J 0
(6225 4975);
DISPLAY 0.872340 (6225 4975);
PAINT GREEN (6225 4975);
DISPLAY INVISIBLE (6225 4975);
FORCEPROP 2 LAST PATH I162
J 0
(6450 5125);
DISPLAY 0.680851 (6450 5125);
DISPLAY INVISIBLE (6450 5125);
FORCEADD OFFPAGE..4
(6250 5125);
FORCEPROP 2 LAST $XR0 139 
J 0
(6436 5125);
DISPLAY 0.638298 (6436 5125);
PAINT MONO (6436 5125);
FORCEPROP 2 LAST CDS_LIB standard
J 0
(6250 5125);
PAINT MONO (6250 5125);
DISPLAY INVISIBLE (6250 5125);
FORCEPROP 1 LAST OFFPAGE TRUE
J 0
(6575 5000);
DISPLAY 0.872340 (6575 5000);
PAINT GREEN (6575 5000);
DISPLAY INVISIBLE (6575 5000);
FORCEPROP 1 LAST COMMENT_BODY TRUE
J 0
(6225 5025);
DISPLAY 0.872340 (6225 5025);
PAINT GREEN (6225 5025);
DISPLAY INVISIBLE (6225 5025);
FORCEPROP 2 LAST PATH I163
J 0
(6450 5175);
DISPLAY 0.680851 (6450 5175);
DISPLAY INVISIBLE (6450 5175);
FORCEADD OFFPAGE..4
(8325 725);
FORCEPROP 2 LAST $XR0 29 
J 0
(8511 725);
DISPLAY 0.638298 (8511 725);
PAINT MONO (8511 725);
FORCEPROP 2 LAST CDS_LIB standard
J 0
(8325 725);
PAINT MONO (8325 725);
DISPLAY INVISIBLE (8325 725);
FORCEPROP 1 LAST OFFPAGE TRUE
J 0
(8650 600);
DISPLAY 0.872340 (8650 600);
PAINT GREEN (8650 600);
DISPLAY INVISIBLE (8650 600);
FORCEPROP 1 LAST COMMENT_BODY TRUE
J 0
(8300 625);
DISPLAY 0.872340 (8300 625);
PAINT GREEN (8300 625);
DISPLAY INVISIBLE (8300 625);
FORCEPROP 2 LAST PATH I164
J 0
(8525 775);
DISPLAY 0.680851 (8525 775);
DISPLAY INVISIBLE (8525 775);
FORCEADD OFFPAGE..4
(8325 775);
FORCEPROP 2 LAST $XR0 29 
J 0
(8511 775);
DISPLAY 0.638298 (8511 775);
PAINT MONO (8511 775);
FORCEPROP 2 LAST CDS_LIB standard
J 0
(8325 775);
PAINT MONO (8325 775);
DISPLAY INVISIBLE (8325 775);
FORCEPROP 1 LAST OFFPAGE TRUE
J 0
(8650 650);
DISPLAY 0.872340 (8650 650);
PAINT GREEN (8650 650);
DISPLAY INVISIBLE (8650 650);
FORCEPROP 1 LAST COMMENT_BODY TRUE
J 0
(8300 675);
DISPLAY 0.872340 (8300 675);
PAINT GREEN (8300 675);
DISPLAY INVISIBLE (8300 675);
FORCEPROP 2 LAST PATH I165
J 0
(8525 825);
DISPLAY 0.680851 (8525 825);
DISPLAY INVISIBLE (8525 825);
FORCEADD TAP..1
R 2
(3100 1175);
FORCEPROP 3 LASTPIN (3150 1175) SIG_NAME P5E_CPU1_G1_TX_C_DN<13>
J 0
(3160 1185);
DISPLAY 0.659574 (3160 1185);
PAINT MONO (3160 1185);
DISPLAY INVISIBLE (3160 1185);
FORCEPROP 1 LASTPIN (3150 1175) BN 13
J 2
(3162 1183);
DISPLAY 0.680851 (3162 1183);
PAINT GREEN (3162 1183);
FORCEPROP 2 LAST CDS_LIB standard
J 0
(3100 1175);
PAINT MONO (3100 1175);
DISPLAY INVISIBLE (3100 1175);
FORCEPROP 1 LAST BODY_TYPE PLUMBING
J 2
(3100 1225);
DISPLAY 0.872340 (3100 1225);
PAINT GREEN (3100 1225);
DISPLAY INVISIBLE (3100 1225);
FORCEPROP 1 LAST HDL_TAP TRUE
J 2
(2775 1050);
DISPLAY 0.872340 (2775 1050);
PAINT GREEN (2775 1050);
DISPLAY INVISIBLE (2775 1050);
FORCEPROP 1 LAST PATH I166
J 2
(3102 1175);
DISPLAY 0.872340 (3102 1175);
PAINT GREEN (3102 1175);
DISPLAY INVISIBLE (3102 1175);
FORCEADD TAP..1
R 2
(3250 1225);
FORCEPROP 3 LASTPIN (3300 1225) SIG_NAME P5E_CPU1_G1_TX_C_DP<13>
J 0
(3310 1235);
DISPLAY 0.659574 (3310 1235);
PAINT MONO (3310 1235);
DISPLAY INVISIBLE (3310 1235);
FORCEPROP 1 LASTPIN (3300 1225) BN 13
J 2
(3312 1233);
DISPLAY 0.680851 (3312 1233);
PAINT GREEN (3312 1233);
FORCEPROP 2 LAST CDS_LIB standard
J 0
(3250 1225);
PAINT MONO (3250 1225);
DISPLAY INVISIBLE (3250 1225);
FORCEPROP 1 LAST BODY_TYPE PLUMBING
J 2
(3250 1275);
DISPLAY 0.872340 (3250 1275);
PAINT GREEN (3250 1275);
DISPLAY INVISIBLE (3250 1275);
FORCEPROP 1 LAST HDL_TAP TRUE
J 2
(2925 1100);
DISPLAY 0.872340 (2925 1100);
PAINT GREEN (2925 1100);
DISPLAY INVISIBLE (2925 1100);
FORCEPROP 1 LAST PATH I167
J 2
(3252 1225);
DISPLAY 0.872340 (3252 1225);
PAINT GREEN (3252 1225);
DISPLAY INVISIBLE (3252 1225);
FORCEADD SCONN168_ME1016810202011..1
(4475 2750);
FORCEPROP 1 LAST LOCATION J35
J 0
(3986 5517);
DISPLAY 0.723404 (3986 5517);
PAINT GREEN (3986 5517);
FORCEPROP 0 LAST $SEC 1
J 0
(4000 5675);
DISPLAY 0.680851 (4000 5675);
PAINT MONO (4000 5675);
DISPLAY INVISIBLE (4000 5675);
FORCEPROP 0 LAST CDS_SEC 1
J 0
(4000 5675);
DISPLAY 1.021277 (4000 5675);
DISPLAY INVISIBLE (4000 5675);
FORCEPROP 0 LASTPIN (3825 3825) $PN B11
J 2
(3815 3835);
DISPLAY 0.680851 (3815 3835);
PAINT MONO (3815 3835);
FORCEPROP 0 LASTPIN (3825 4325) $PN B1
J 2
(3815 4335);
DISPLAY 0.680851 (3815 4335);
PAINT MONO (3815 4335);
FORCEPROP 0 LASTPIN (3825 4275) $PN B2
J 2
(3815 4285);
DISPLAY 0.680851 (3815 4285);
PAINT MONO (3815 4285);
FORCEPROP 0 LASTPIN (3825 4225) $PN B3
J 2
(3815 4235);
DISPLAY 0.680851 (3815 4235);
PAINT MONO (3815 4235);
FORCEPROP 0 LASTPIN (3825 4175) $PN B4
J 2
(3815 4185);
DISPLAY 0.680851 (3815 4185);
PAINT MONO (3815 4185);
FORCEPROP 0 LASTPIN (3825 4125) $PN B5
J 2
(3815 4135);
DISPLAY 0.680851 (3815 4135);
PAINT MONO (3815 4135);
FORCEPROP 0 LASTPIN (3825 4075) $PN B6
J 2
(3815 4085);
DISPLAY 0.680851 (3815 4085);
PAINT MONO (3815 4085);
FORCEPROP 0 LASTPIN (3825 3775) $PN B12
J 2
(3815 3785);
DISPLAY 0.680851 (3815 3785);
PAINT MONO (3815 3785);
FORCEPROP 0 LASTPIN (3825 4025) $PN B7
J 2
(3815 4035);
DISPLAY 0.680851 (3815 4035);
PAINT MONO (3815 4035);
FORCEPROP 0 LASTPIN (3825 3975) $PN B8
J 2
(3815 3985);
DISPLAY 0.680851 (3815 3985);
PAINT MONO (3815 3985);
FORCEPROP 0 LASTPIN (3825 3925) $PN B9
J 2
(3815 3935);
DISPLAY 0.680851 (3815 3935);
PAINT MONO (3815 3935);
FORCEPROP 0 LASTPIN (3825 4875) $PN OB6
J 2
(3815 4885);
DISPLAY 0.680851 (3815 4885);
PAINT MONO (3815 4885);
FORCEPROP 0 LASTPIN (3825 4975) $PN OB4
J 2
(3815 4985);
DISPLAY 0.680851 (3815 4985);
PAINT MONO (3815 4985);
FORCEPROP 0 LASTPIN (3825 4925) $PN OB5
J 2
(3815 4935);
DISPLAY 0.680851 (3815 4935);
PAINT MONO (3815 4935);
FORCEPROP 0 LASTPIN (5125 575) $PN G1
J 0
(5135 585);
DISPLAY 0.680851 (5135 585);
PAINT MONO (5135 585);
FORCEPROP 0 LASTPIN (5125 525) $PN G2
J 0
(5135 535);
DISPLAY 0.680851 (5135 535);
PAINT MONO (5135 535);
FORCEPROP 0 LASTPIN (5125 475) $PN G3
J 0
(5135 485);
DISPLAY 0.680851 (5135 485);
PAINT MONO (5135 485);
FORCEPROP 0 LASTPIN (5125 425) $PN G4
J 0
(5135 435);
DISPLAY 0.680851 (5135 435);
PAINT MONO (5135 435);
FORCEPROP 0 LASTPIN (5125 375) $PN G5
J 0
(5135 385);
DISPLAY 0.680851 (5135 385);
PAINT MONO (5135 385);
FORCEPROP 0 LASTPIN (5125 4325) $PN A1
J 0
(5135 4335);
DISPLAY 0.680851 (5135 4335);
PAINT MONO (5135 4335);
FORCEPROP 0 LASTPIN (5125 4275) $PN A2
J 0
(5135 4285);
DISPLAY 0.680851 (5135 4285);
PAINT MONO (5135 4285);
FORCEPROP 0 LASTPIN (5125 4225) $PN A3
J 0
(5135 4235);
DISPLAY 0.680851 (5135 4235);
PAINT MONO (5135 4235);
FORCEPROP 0 LASTPIN (5125 4175) $PN A4
J 0
(5135 4185);
DISPLAY 0.680851 (5135 4185);
PAINT MONO (5135 4185);
FORCEPROP 0 LASTPIN (5125 4125) $PN A5
J 0
(5135 4135);
DISPLAY 0.680851 (5135 4135);
PAINT MONO (5135 4135);
FORCEPROP 0 LASTPIN (5125 4075) $PN A6
J 0
(5135 4085);
DISPLAY 0.680851 (5135 4085);
PAINT MONO (5135 4085);
FORCEPROP 0 LASTPIN (5125 3725) $PN A13
J 0
(5135 3735);
DISPLAY 0.680851 (5135 3735);
PAINT MONO (5135 3735);
FORCEPROP 0 LASTPIN (5125 3575) $PN A16
J 0
(5135 3585);
DISPLAY 0.680851 (5135 3585);
PAINT MONO (5135 3585);
FORCEPROP 0 LASTPIN (5125 3425) $PN A19
J 0
(5135 3435);
DISPLAY 0.680851 (5135 3435);
PAINT MONO (5135 3435);
FORCEPROP 0 LASTPIN (5125 3275) $PN A22
J 0
(5135 3285);
DISPLAY 0.680851 (5135 3285);
PAINT MONO (5135 3285);
FORCEPROP 0 LASTPIN (5125 3125) $PN A25
J 0
(5135 3135);
DISPLAY 0.680851 (5135 3135);
PAINT MONO (5135 3135);
FORCEPROP 0 LASTPIN (5125 2975) $PN A28
J 0
(5135 2985);
DISPLAY 0.680851 (5135 2985);
PAINT MONO (5135 2985);
FORCEPROP 0 LASTPIN (5125 2825) $PN A29
J 0
(5135 2835);
DISPLAY 0.680851 (5135 2835);
PAINT MONO (5135 2835);
FORCEPROP 0 LASTPIN (5125 2675) $PN A32
J 0
(5135 2685);
DISPLAY 0.680851 (5135 2685);
PAINT MONO (5135 2685);
FORCEPROP 0 LASTPIN (5125 2525) $PN A35
J 0
(5135 2535);
DISPLAY 0.680851 (5135 2535);
PAINT MONO (5135 2535);
FORCEPROP 0 LASTPIN (5125 2375) $PN A38
J 0
(5135 2385);
DISPLAY 0.680851 (5135 2385);
PAINT MONO (5135 2385);
FORCEPROP 0 LASTPIN (5125 2225) $PN A41
J 0
(5135 2235);
DISPLAY 0.680851 (5135 2235);
PAINT MONO (5135 2235);
FORCEPROP 0 LASTPIN (5125 2025) $PN A43
J 0
(5135 2035);
DISPLAY 0.680851 (5135 2035);
PAINT MONO (5135 2035);
FORCEPROP 0 LASTPIN (5125 1875) $PN A46
J 0
(5135 1885);
DISPLAY 0.680851 (5135 1885);
PAINT MONO (5135 1885);
FORCEPROP 0 LASTPIN (5125 1725) $PN A49
J 0
(5135 1735);
DISPLAY 0.680851 (5135 1735);
PAINT MONO (5135 1735);
FORCEPROP 0 LASTPIN (5125 1575) $PN A52
J 0
(5135 1585);
DISPLAY 0.680851 (5135 1585);
PAINT MONO (5135 1585);
FORCEPROP 0 LASTPIN (5125 1425) $PN A55
J 0
(5135 1435);
DISPLAY 0.680851 (5135 1435);
PAINT MONO (5135 1435);
FORCEPROP 0 LASTPIN (5125 1275) $PN A58
J 0
(5135 1285);
DISPLAY 0.680851 (5135 1285);
PAINT MONO (5135 1285);
FORCEPROP 0 LASTPIN (5125 1125) $PN A61
J 0
(5135 1135);
DISPLAY 0.680851 (5135 1135);
PAINT MONO (5135 1135);
FORCEPROP 0 LASTPIN (5125 975) $PN A64
J 0
(5135 985);
DISPLAY 0.680851 (5135 985);
PAINT MONO (5135 985);
FORCEPROP 0 LASTPIN (5125 825) $PN A67
J 0
(5135 835);
DISPLAY 0.680851 (5135 835);
PAINT MONO (5135 835);
FORCEPROP 0 LASTPIN (3825 3725) $PN B13
J 2
(3815 3735);
DISPLAY 0.680851 (3815 3735);
PAINT MONO (3815 3735);
FORCEPROP 0 LASTPIN (3825 3575) $PN B16
J 2
(3815 3585);
DISPLAY 0.680851 (3815 3585);
PAINT MONO (3815 3585);
FORCEPROP 0 LASTPIN (3825 3425) $PN B19
J 2
(3815 3435);
DISPLAY 0.680851 (3815 3435);
PAINT MONO (3815 3435);
FORCEPROP 0 LASTPIN (3825 3275) $PN B22
J 2
(3815 3285);
DISPLAY 0.680851 (3815 3285);
PAINT MONO (3815 3285);
FORCEPROP 0 LASTPIN (3825 3125) $PN B25
J 2
(3815 3135);
DISPLAY 0.680851 (3815 3135);
PAINT MONO (3815 3135);
FORCEPROP 0 LASTPIN (3825 2975) $PN B28
J 2
(3815 2985);
DISPLAY 0.680851 (3815 2985);
PAINT MONO (3815 2985);
FORCEPROP 0 LASTPIN (3825 2825) $PN B29
J 2
(3815 2835);
DISPLAY 0.680851 (3815 2835);
PAINT MONO (3815 2835);
FORCEPROP 0 LASTPIN (3825 2675) $PN B32
J 2
(3815 2685);
DISPLAY 0.680851 (3815 2685);
PAINT MONO (3815 2685);
FORCEPROP 0 LASTPIN (3825 2525) $PN B35
J 2
(3815 2535);
DISPLAY 0.680851 (3815 2535);
PAINT MONO (3815 2535);
FORCEPROP 0 LASTPIN (3825 2375) $PN B38
J 2
(3815 2385);
DISPLAY 0.680851 (3815 2385);
PAINT MONO (3815 2385);
FORCEPROP 0 LASTPIN (3825 2225) $PN B41
J 2
(3815 2235);
DISPLAY 0.680851 (3815 2235);
PAINT MONO (3815 2235);
FORCEPROP 0 LASTPIN (3825 2025) $PN B43
J 2
(3815 2035);
DISPLAY 0.680851 (3815 2035);
PAINT MONO (3815 2035);
FORCEPROP 0 LASTPIN (3825 1875) $PN B46
J 2
(3815 1885);
DISPLAY 0.680851 (3815 1885);
PAINT MONO (3815 1885);
FORCEPROP 0 LASTPIN (3825 1725) $PN B49
J 2
(3815 1735);
DISPLAY 0.680851 (3815 1735);
PAINT MONO (3815 1735);
FORCEPROP 0 LASTPIN (3825 1575) $PN B52
J 2
(3815 1585);
DISPLAY 0.680851 (3815 1585);
PAINT MONO (3815 1585);
FORCEPROP 0 LASTPIN (3825 1425) $PN B55
J 2
(3815 1435);
DISPLAY 0.680851 (3815 1435);
PAINT MONO (3815 1435);
FORCEPROP 0 LASTPIN (3825 1275) $PN B58
J 2
(3815 1285);
DISPLAY 0.680851 (3815 1285);
PAINT MONO (3815 1285);
FORCEPROP 0 LASTPIN (3825 1125) $PN B61
J 2
(3815 1135);
DISPLAY 0.680851 (3815 1135);
PAINT MONO (3815 1135);
FORCEPROP 0 LASTPIN (3825 975) $PN B64
J 2
(3815 985);
DISPLAY 0.680851 (3815 985);
PAINT MONO (3815 985);
FORCEPROP 0 LASTPIN (3825 825) $PN B67
J 2
(3815 835);
DISPLAY 0.680851 (3815 835);
PAINT MONO (3815 835);
FORCEPROP 0 LASTPIN (5125 4675) $PN OA10
J 0
(5135 4685);
DISPLAY 0.680851 (5135 4685);
PAINT MONO (5135 4685);
FORCEPROP 0 LASTPIN (5125 4525) $PN OA13
J 0
(5135 4535);
DISPLAY 0.680851 (5135 4535);
PAINT MONO (5135 4535);
FORCEPROP 0 LASTPIN (3825 4675) $PN OB10
J 2
(3815 4685);
DISPLAY 0.680851 (3815 4685);
PAINT MONO (3815 4685);
FORCEPROP 0 LASTPIN (3825 4525) $PN OB13
J 2
(3815 4535);
DISPLAY 0.680851 (3815 4535);
PAINT MONO (3815 4535);
FORCEPROP 0 LASTPIN (3825 5025) $PN OB3
J 2
(3815 5035);
DISPLAY 0.680851 (3815 5035);
PAINT MONO (3815 5035);
FORCEPROP 0 LASTPIN (3825 5075) $PN OB2
J 2
(3815 5085);
DISPLAY 0.680851 (3815 5085);
PAINT MONO (3815 5085);
FORCEPROP 0 LASTPIN (3825 5125) $PN OB1
J 2
(3815 5135);
DISPLAY 0.680851 (3815 5135);
PAINT MONO (3815 5135);
FORCEPROP 0 LASTPIN (5125 3525) $PN A17
J 0
(5135 3535);
DISPLAY 0.680851 (5135 3535);
PAINT MONO (5135 3535);
FORCEPROP 0 LASTPIN (5125 3375) $PN A20
J 0
(5135 3385);
DISPLAY 0.680851 (5135 3385);
PAINT MONO (5135 3385);
FORCEPROP 0 LASTPIN (5125 3225) $PN A23
J 0
(5135 3235);
DISPLAY 0.680851 (5135 3235);
PAINT MONO (5135 3235);
FORCEPROP 0 LASTPIN (5125 3075) $PN A26
J 0
(5135 3085);
DISPLAY 0.680851 (5135 3085);
PAINT MONO (5135 3085);
FORCEPROP 0 LASTPIN (5125 2775) $PN A30
J 0
(5135 2785);
DISPLAY 0.680851 (5135 2785);
PAINT MONO (5135 2785);
FORCEPROP 0 LASTPIN (5125 2625) $PN A33
J 0
(5135 2635);
DISPLAY 0.680851 (5135 2635);
PAINT MONO (5135 2635);
FORCEPROP 0 LASTPIN (5125 2475) $PN A36
J 0
(5135 2485);
DISPLAY 0.680851 (5135 2485);
PAINT MONO (5135 2485);
FORCEPROP 0 LASTPIN (5125 2325) $PN A39
J 0
(5135 2335);
DISPLAY 0.680851 (5135 2335);
PAINT MONO (5135 2335);
FORCEPROP 0 LASTPIN (5125 1975) $PN A44
J 0
(5135 1985);
DISPLAY 0.680851 (5135 1985);
PAINT MONO (5135 1985);
FORCEPROP 0 LASTPIN (5125 1825) $PN A47
J 0
(5135 1835);
DISPLAY 0.680851 (5135 1835);
PAINT MONO (5135 1835);
FORCEPROP 0 LASTPIN (5125 1675) $PN A50
J 0
(5135 1685);
DISPLAY 0.680851 (5135 1685);
PAINT MONO (5135 1685);
FORCEPROP 0 LASTPIN (5125 1525) $PN A53
J 0
(5135 1535);
DISPLAY 0.680851 (5135 1535);
PAINT MONO (5135 1535);
FORCEPROP 0 LASTPIN (5125 1375) $PN A56
J 0
(5135 1385);
DISPLAY 0.680851 (5135 1385);
PAINT MONO (5135 1385);
FORCEPROP 0 LASTPIN (5125 1225) $PN A59
J 0
(5135 1235);
DISPLAY 0.680851 (5135 1235);
PAINT MONO (5135 1235);
FORCEPROP 0 LASTPIN (5125 1075) $PN A62
J 0
(5135 1085);
DISPLAY 0.680851 (5135 1085);
PAINT MONO (5135 1085);
FORCEPROP 0 LASTPIN (5125 925) $PN A65
J 0
(5135 935);
DISPLAY 0.680851 (5135 935);
PAINT MONO (5135 935);
FORCEPROP 0 LASTPIN (5125 3475) $PN A18
J 0
(5135 3485);
DISPLAY 0.680851 (5135 3485);
PAINT MONO (5135 3485);
FORCEPROP 0 LASTPIN (5125 3325) $PN A21
J 0
(5135 3335);
DISPLAY 0.680851 (5135 3335);
PAINT MONO (5135 3335);
FORCEPROP 0 LASTPIN (5125 3175) $PN A24
J 0
(5135 3185);
DISPLAY 0.680851 (5135 3185);
PAINT MONO (5135 3185);
FORCEPROP 0 LASTPIN (5125 3025) $PN A27
J 0
(5135 3035);
DISPLAY 0.680851 (5135 3035);
PAINT MONO (5135 3035);
FORCEPROP 0 LASTPIN (5125 2725) $PN A31
J 0
(5135 2735);
DISPLAY 0.680851 (5135 2735);
PAINT MONO (5135 2735);
FORCEPROP 0 LASTPIN (5125 2575) $PN A34
J 0
(5135 2585);
DISPLAY 0.680851 (5135 2585);
PAINT MONO (5135 2585);
FORCEPROP 0 LASTPIN (5125 2425) $PN A37
J 0
(5135 2435);
DISPLAY 0.680851 (5135 2435);
PAINT MONO (5135 2435);
FORCEPROP 0 LASTPIN (5125 2275) $PN A40
J 0
(5135 2285);
DISPLAY 0.680851 (5135 2285);
PAINT MONO (5135 2285);
FORCEPROP 0 LASTPIN (5125 1925) $PN A45
J 0
(5135 1935);
DISPLAY 0.680851 (5135 1935);
PAINT MONO (5135 1935);
FORCEPROP 0 LASTPIN (5125 1775) $PN A48
J 0
(5135 1785);
DISPLAY 0.680851 (5135 1785);
PAINT MONO (5135 1785);
FORCEPROP 0 LASTPIN (5125 1625) $PN A51
J 0
(5135 1635);
DISPLAY 0.680851 (5135 1635);
PAINT MONO (5135 1635);
FORCEPROP 0 LASTPIN (5125 1475) $PN A54
J 0
(5135 1485);
DISPLAY 0.680851 (5135 1485);
PAINT MONO (5135 1485);
FORCEPROP 0 LASTPIN (5125 1325) $PN A57
J 0
(5135 1335);
DISPLAY 0.680851 (5135 1335);
PAINT MONO (5135 1335);
FORCEPROP 0 LASTPIN (5125 1175) $PN A60
J 0
(5135 1185);
DISPLAY 0.680851 (5135 1185);
PAINT MONO (5135 1185);
FORCEPROP 0 LASTPIN (5125 1025) $PN A63
J 0
(5135 1035);
DISPLAY 0.680851 (5135 1035);
PAINT MONO (5135 1035);
FORCEPROP 0 LASTPIN (5125 875) $PN A66
J 0
(5135 885);
DISPLAY 0.680851 (5135 885);
PAINT MONO (5135 885);
FORCEPROP 0 LASTPIN (3825 3875) $PN B10
J 2
(3815 3885);
DISPLAY 0.680851 (3815 3885);
PAINT MONO (3815 3885);
FORCEPROP 0 LASTPIN (5125 3825) $PN A11
J 0
(5135 3835);
DISPLAY 0.680851 (5135 3835);
PAINT MONO (5135 3835);
FORCEPROP 0 LASTPIN (5125 5125) $PN OA1
J 0
(5135 5135);
DISPLAY 0.680851 (5135 5135);
PAINT MONO (5135 5135);
FORCEPROP 0 LASTPIN (5125 5075) $PN OA2
J 0
(5135 5085);
DISPLAY 0.680851 (5135 5085);
PAINT MONO (5135 5085);
FORCEPROP 0 LASTPIN (3825 3525) $PN B17
J 2
(3815 3535);
DISPLAY 0.680851 (3815 3535);
PAINT MONO (3815 3535);
FORCEPROP 0 LASTPIN (3825 3375) $PN B20
J 2
(3815 3385);
DISPLAY 0.680851 (3815 3385);
PAINT MONO (3815 3385);
FORCEPROP 0 LASTPIN (3825 3225) $PN B23
J 2
(3815 3235);
DISPLAY 0.680851 (3815 3235);
PAINT MONO (3815 3235);
FORCEPROP 0 LASTPIN (3825 3075) $PN B26
J 2
(3815 3085);
DISPLAY 0.680851 (3815 3085);
PAINT MONO (3815 3085);
FORCEPROP 0 LASTPIN (3825 2775) $PN B30
J 2
(3815 2785);
DISPLAY 0.680851 (3815 2785);
PAINT MONO (3815 2785);
FORCEPROP 0 LASTPIN (3825 2625) $PN B33
J 2
(3815 2635);
DISPLAY 0.680851 (3815 2635);
PAINT MONO (3815 2635);
FORCEPROP 0 LASTPIN (3825 2475) $PN B36
J 2
(3815 2485);
DISPLAY 0.680851 (3815 2485);
PAINT MONO (3815 2485);
FORCEPROP 0 LASTPIN (3825 2325) $PN B39
J 2
(3815 2335);
DISPLAY 0.680851 (3815 2335);
PAINT MONO (3815 2335);
FORCEPROP 0 LASTPIN (3825 1975) $PN B44
J 2
(3815 1985);
DISPLAY 0.680851 (3815 1985);
PAINT MONO (3815 1985);
FORCEPROP 0 LASTPIN (3825 1825) $PN B47
J 2
(3815 1835);
DISPLAY 0.680851 (3815 1835);
PAINT MONO (3815 1835);
FORCEPROP 0 LASTPIN (3825 1675) $PN B50
J 2
(3815 1685);
DISPLAY 0.680851 (3815 1685);
PAINT MONO (3815 1685);
FORCEPROP 0 LASTPIN (3825 1525) $PN B53
J 2
(3815 1535);
DISPLAY 0.680851 (3815 1535);
PAINT MONO (3815 1535);
FORCEPROP 0 LASTPIN (3825 1375) $PN B56
J 2
(3815 1385);
DISPLAY 0.680851 (3815 1385);
PAINT MONO (3815 1385);
FORCEPROP 0 LASTPIN (3825 1225) $PN B59
J 2
(3815 1235);
DISPLAY 0.680851 (3815 1235);
PAINT MONO (3815 1235);
FORCEPROP 0 LASTPIN (3825 1075) $PN B62
J 2
(3815 1085);
DISPLAY 0.680851 (3815 1085);
PAINT MONO (3815 1085);
FORCEPROP 0 LASTPIN (3825 925) $PN B65
J 2
(3815 935);
DISPLAY 0.680851 (3815 935);
PAINT MONO (3815 935);
FORCEPROP 0 LASTPIN (3825 3475) $PN B18
J 2
(3815 3485);
DISPLAY 0.680851 (3815 3485);
PAINT MONO (3815 3485);
FORCEPROP 0 LASTPIN (3825 3325) $PN B21
J 2
(3815 3335);
DISPLAY 0.680851 (3815 3335);
PAINT MONO (3815 3335);
FORCEPROP 0 LASTPIN (3825 3175) $PN B24
J 2
(3815 3185);
DISPLAY 0.680851 (3815 3185);
PAINT MONO (3815 3185);
FORCEPROP 0 LASTPIN (3825 3025) $PN B27
J 2
(3815 3035);
DISPLAY 0.680851 (3815 3035);
PAINT MONO (3815 3035);
FORCEPROP 0 LASTPIN (3825 2725) $PN B31
J 2
(3815 2735);
DISPLAY 0.680851 (3815 2735);
PAINT MONO (3815 2735);
FORCEPROP 0 LASTPIN (3825 2575) $PN B34
J 2
(3815 2585);
DISPLAY 0.680851 (3815 2585);
PAINT MONO (3815 2585);
FORCEPROP 0 LASTPIN (3825 2425) $PN B37
J 2
(3815 2435);
DISPLAY 0.680851 (3815 2435);
PAINT MONO (3815 2435);
FORCEPROP 0 LASTPIN (3825 2275) $PN B40
J 2
(3815 2285);
DISPLAY 0.680851 (3815 2285);
PAINT MONO (3815 2285);
FORCEPROP 0 LASTPIN (3825 1925) $PN B45
J 2
(3815 1935);
DISPLAY 0.680851 (3815 1935);
PAINT MONO (3815 1935);
FORCEPROP 0 LASTPIN (3825 1775) $PN B48
J 2
(3815 1785);
DISPLAY 0.680851 (3815 1785);
PAINT MONO (3815 1785);
FORCEPROP 0 LASTPIN (3825 1625) $PN B51
J 2
(3815 1635);
DISPLAY 0.680851 (3815 1635);
PAINT MONO (3815 1635);
FORCEPROP 0 LASTPIN (3825 1475) $PN B54
J 2
(3815 1485);
DISPLAY 0.680851 (3815 1485);
PAINT MONO (3815 1485);
FORCEPROP 0 LASTPIN (3825 1325) $PN B57
J 2
(3815 1335);
DISPLAY 0.680851 (3815 1335);
PAINT MONO (3815 1335);
FORCEPROP 0 LASTPIN (3825 1175) $PN B60
J 2
(3815 1185);
DISPLAY 0.680851 (3815 1185);
PAINT MONO (3815 1185);
FORCEPROP 0 LASTPIN (3825 1025) $PN B63
J 2
(3815 1035);
DISPLAY 0.680851 (3815 1035);
PAINT MONO (3815 1035);
FORCEPROP 0 LASTPIN (3825 875) $PN B66
J 2
(3815 885);
DISPLAY 0.680851 (3815 885);
PAINT MONO (3815 885);
FORCEPROP 0 LASTPIN (5125 3875) $PN A10
J 0
(5135 3885);
DISPLAY 0.680851 (5135 3885);
PAINT MONO (5135 3885);
FORCEPROP 0 LASTPIN (3825 2175) $PN B42
J 2
(3815 2185);
DISPLAY 0.680851 (3815 2185);
PAINT MONO (3815 2185);
FORCEPROP 0 LASTPIN (5125 2175) $PN A42
J 0
(5135 2185);
DISPLAY 0.680851 (5135 2185);
PAINT MONO (5135 2185);
FORCEPROP 0 LASTPIN (5125 3775) $PN A12
J 0
(5135 3785);
DISPLAY 0.680851 (5135 3785);
PAINT MONO (5135 3785);
FORCEPROP 0 LASTPIN (3825 675) $PN B70
J 2
(3815 685);
DISPLAY 0.680851 (3815 685);
PAINT MONO (3815 685);
FORCEPROP 0 LASTPIN (5125 675) $PN A70
J 0
(5135 685);
DISPLAY 0.680851 (5135 685);
PAINT MONO (5135 685);
FORCEPROP 0 LASTPIN (5125 4975) $PN OA4
J 0
(5135 4985);
DISPLAY 0.680851 (5135 4985);
PAINT MONO (5135 4985);
FORCEPROP 0 LASTPIN (5125 4925) $PN OA5
J 0
(5135 4935);
DISPLAY 0.680851 (5135 4935);
PAINT MONO (5135 4935);
FORCEPROP 0 LASTPIN (5125 4475) $PN OA14
J 0
(5135 4485);
DISPLAY 0.680851 (5135 4485);
PAINT MONO (5135 4485);
FORCEPROP 0 LASTPIN (3825 4475) $PN OB14
J 2
(3815 4485);
DISPLAY 0.680851 (3815 4485);
PAINT MONO (3815 4485);
FORCEPROP 0 LASTPIN (3825 4725) $PN OB9
J 2
(3815 4735);
DISPLAY 0.680851 (3815 4735);
PAINT MONO (3815 4735);
FORCEPROP 0 LASTPIN (3825 4775) $PN OB8
J 2
(3815 4785);
DISPLAY 0.680851 (3815 4785);
PAINT MONO (3815 4785);
FORCEPROP 0 LASTPIN (5125 4825) $PN OA7
J 0
(5135 4835);
DISPLAY 0.680851 (5135 4835);
PAINT MONO (5135 4835);
FORCEPROP 0 LASTPIN (5125 4725) $PN OA9
J 0
(5135 4735);
DISPLAY 0.680851 (5135 4735);
PAINT MONO (5135 4735);
FORCEPROP 0 LASTPIN (5125 4775) $PN OA8
J 0
(5135 4785);
DISPLAY 0.680851 (5135 4785);
PAINT MONO (5135 4785);
FORCEPROP 0 LASTPIN (3825 3675) $PN B14
J 2
(3815 3685);
DISPLAY 0.680851 (3815 3685);
PAINT MONO (3815 3685);
FORCEPROP 0 LASTPIN (5125 3675) $PN A14
J 0
(5135 3685);
DISPLAY 0.680851 (5135 3685);
PAINT MONO (5135 3685);
FORCEPROP 0 LASTPIN (3825 4625) $PN OB11
J 2
(3815 4635);
DISPLAY 0.680851 (3815 4635);
PAINT MONO (3815 4635);
FORCEPROP 0 LASTPIN (5125 4625) $PN OA11
J 0
(5135 4635);
DISPLAY 0.680851 (5135 4635);
PAINT MONO (5135 4635);
FORCEPROP 0 LASTPIN (3825 3625) $PN B15
J 2
(3815 3635);
DISPLAY 0.680851 (3815 3635);
PAINT MONO (3815 3635);
FORCEPROP 0 LASTPIN (5125 3625) $PN A15
J 0
(5135 3635);
DISPLAY 0.680851 (5135 3635);
PAINT MONO (5135 3635);
FORCEPROP 0 LASTPIN (3825 4575) $PN OB12
J 2
(3815 4585);
DISPLAY 0.680851 (3815 4585);
PAINT MONO (3815 4585);
FORCEPROP 0 LASTPIN (5125 4575) $PN OA12
J 0
(5135 4585);
DISPLAY 0.680851 (5135 4585);
PAINT MONO (5135 4585);
FORCEPROP 0 LASTPIN (3825 775) $PN B68
J 2
(3815 785);
DISPLAY 0.680851 (3815 785);
PAINT MONO (3815 785);
FORCEPROP 0 LASTPIN (3825 725) $PN B69
J 2
(3815 735);
DISPLAY 0.680851 (3815 735);
PAINT MONO (3815 735);
FORCEPROP 0 LASTPIN (3825 4825) $PN OB7
J 2
(3815 4835);
DISPLAY 0.680851 (3815 4835);
PAINT MONO (3815 4835);
FORCEPROP 0 LASTPIN (5125 4875) $PN OA6
J 0
(5135 4885);
DISPLAY 0.680851 (5135 4885);
PAINT MONO (5135 4885);
FORCEPROP 0 LASTPIN (5125 4025) $PN A7
J 0
(5135 4035);
DISPLAY 0.680851 (5135 4035);
PAINT MONO (5135 4035);
FORCEPROP 0 LASTPIN (5125 3975) $PN A8
J 0
(5135 3985);
DISPLAY 0.680851 (5135 3985);
PAINT MONO (5135 3985);
FORCEPROP 0 LASTPIN (5125 3925) $PN A9
J 0
(5135 3935);
DISPLAY 0.680851 (5135 3935);
PAINT MONO (5135 3935);
FORCEPROP 0 LASTPIN (5125 775) $PN A68
J 0
(5135 785);
DISPLAY 0.680851 (5135 785);
PAINT MONO (5135 785);
FORCEPROP 0 LASTPIN (5125 725) $PN A69
J 0
(5135 735);
DISPLAY 0.680851 (5135 735);
PAINT MONO (5135 735);
FORCEPROP 0 LASTPIN (5125 5025) $PN OA3
J 0
(5135 5035);
DISPLAY 0.680851 (5135 5035);
PAINT MONO (5135 5035);
FORCEPROP 2 LAST VALUE SCONN168_ME1016810202011
J 0
(4000 5575);
DISPLAY 1.021277 (4000 5575);
FORCEPROP 2 LAST PART_TYPE SMLF
J 0
(4000 5625);
DISPLAY 1.021277 (4000 5625);
FORCEPROP 1 LAST MATERIAL IO
J 0
(3986 5243);
DISPLAY 0.723404 (3986 5243);
PAINT GREEN (3986 5243);
FORCEPROP 1 LAST NEEDS_NO_SIZE TRUE
J 0
(4475 2750);
DISPLAY 0.723404 (4475 2750);
PAINT GREEN (4475 2750);
DISPLAY INVISIBLE (4475 2750);
FORCEPROP 1 LAST CDS_LMAN_SYM_OUTLINE -500,2475,500,-2475
J 0
(4475 2750);
DISPLAY 0.468085 (4475 2750);
PAINT GREEN (4475 2750);
DISPLAY INVISIBLE (4475 2750);
FORCEPROP 2 LAST CDS_LIB pure_quanta
J 0
(4475 2750);
DISPLAY INVISIBLE (4475 2750);
FORCEPROP 1 LAST PATH I168
J 0
(4475 2750);
DISPLAY 0.723404 (4475 2750);
PAINT GREEN (4475 2750);
DISPLAY INVISIBLE (4475 2750);
FORCEPROP 1 LAST PART_NUMBER DFHSG8FR011
J 0
(3986 5370);
DISPLAY 0.723404 (3986 5370);
PAINT GREEN (3986 5370);
DISPLAY INVISIBLE (3986 5370);
FORCEADD UNIVERSAL_GND..1
(4200 -750);
FORCEPROP 3 LASTPIN (4200 -700) SIG_NAME GND\g
J 0
(4210 -690);
DISPLAY 0.659574 (4210 -690);
PAINT MONO (4210 -690);
DISPLAY INVISIBLE (4210 -690);
FORCEPROP 2 LAST CDS_LIB pure_quanta_power
J 0
(4200 -750);
DISPLAY INVISIBLE (4200 -750);
FORCEPROP 1 LAST HDL_POWER GND
J 1
(4225 -825);
DISPLAY 0.872340 (4225 -825);
PAINT GREEN (4225 -825);
DISPLAY INVISIBLE (4225 -825);
FORCEPROP 1 LAST PATH I169
J 0
(4275 -750);
DISPLAY 0.872340 (4275 -750);
PAINT AQUA (4275 -750);
DISPLAY INVISIBLE (4275 -750);
FORCEADD Q_CAP..1
(6925 -300);
FORCEPROP 1 LAST LOCATION C1833
J 0
(6975 -200);
DISPLAY 0.787234 (6975 -200);
FORCEPROP 2 LAST $SEC 1
J 0
(6975 -100);
DISPLAY 0.680851 (6975 -100);
PAINT MONO (6975 -100);
DISPLAY INVISIBLE (6975 -100);
FORCEPROP 2 LAST CDS_SEC 1
J 0
(6975 -100);
DISPLAY 1.021277 (6975 -100);
DISPLAY INVISIBLE (6975 -100);
FORCEPROP 1 LASTPIN (6925 -200) $PN 1
J 0
(6935 -220);
DISPLAY 0.787234 (6935 -220);
FORCEPROP 1 LASTPIN (6925 -400) $PN 2
J 0
(6935 -420);
DISPLAY 0.787234 (6935 -420);
FORCEPROP 1 LAST PACK_TYPE 0402
J 0
(6975 -450);
DISPLAY 0.638298 (6975 -450);
FORCEPROP 1 LAST VALUE 0.1UF
J 0
(6975 -250);
DISPLAY 0.638298 (6975 -250);
FORCEPROP 1 LAST MATERIAL X7R
J 0
(6975 -400);
DISPLAY 0.638298 (6975 -400);
FORCEPROP 1 LAST VOLTAGE 25V
J 0
(6975 -300);
DISPLAY 0.638298 (6975 -300);
FORCEPROP 1 LAST TOLERANCE 10%
J 0
(6975 -350);
DISPLAY 0.638298 (6975 -350);
FORCEPROP 2 LAST CDS_LIB pure_quanta
J 0
(6925 -300);
PAINT MONO (6925 -300);
DISPLAY INVISIBLE (6925 -300);
FORCEPROP 1 LAST PATH I17
J 0
(6975 -150);
DISPLAY 0.978723 (6975 -150);
PAINT WHITE (6975 -150);
DISPLAY INVISIBLE (6975 -150);
FORCEPROP 1 LAST PART_NUMBER CH4104K1B00
J 0
(6975 -450);
DISPLAY 0.808511 (6975 -450);
DISPLAY INVISIBLE (6975 -450);
FORCEADD Q_RES..1
(6375 3975);
FORCEPROP 1 LAST LOCATION R3229
J 0
(6125 3975);
DISPLAY 0.808511 (6125 3975);
FORCEPROP 2 LAST SEC 1
J 0
(6325 4175);
DISPLAY 0.680851 (6325 4175);
PAINT MONO (6325 4175);
DISPLAY INVISIBLE (6325 4175);
FORCEPROP 1 LASTPIN (6275 3975) $PN 1
J 0
(6287 3987);
DISPLAY 0.638298 (6287 3987);
PAINT MONO (6287 3987);
FORCEPROP 1 LASTPIN (6475 3975) $PN 2
J 0
(6437 3987);
DISPLAY 0.638298 (6437 3987);
PAINT MONO (6437 3987);
FORCEPROP 1 LAST PACK_TYPE 0402LF
J 0
(6700 3975);
DISPLAY 0.510638 (6700 3975);
FORCEPROP 1 LAST WATTAGE 1/16W
J 2
(6950 3950);
DISPLAY 0.510638 (6950 3950);
FORCEPROP 1 LAST VALUE 200
J 2
(6600 3975);
DISPLAY 0.510638 (6600 3975);
FORCEPROP 1 LAST TOLERANCE 1%
J 0
(6625 3975);
DISPLAY 0.510638 (6625 3975);
FORCEPROP 1 LAST MATERIAL CHIP
J 0
(6425 3950);
DISPLAY 0.510638 (6425 3950);
FORCEPROP 2 LAST CDS_LIB pure_quanta
J 0
(6375 3975);
DISPLAY INVISIBLE (6375 3975);
FORCEPROP 2 LAST SEC_TYPE 0402LF
J 0
(6325 4175);
DISPLAY 0.680851 (6325 4175);
DISPLAY INVISIBLE (6325 4175);
FORCEPROP 1 LAST PATH I170
J 0
(6325 4125);
DISPLAY 0.978723 (6325 4125);
PAINT WHITE (6325 4125);
DISPLAY INVISIBLE (6325 4125);
FORCEPROP 1 LAST PART_NUMBER CS12002FB06
J 0
(6550 3950);
DISPLAY 0.510638 (6550 3950);
DISPLAY INVISIBLE (6550 3950);
FORCEADD Q_RES..1
(6375 4025);
FORCEPROP 1 LAST LOCATION R3228
J 0
(6125 4025);
DISPLAY 0.638298 (6125 4025);
FORCEPROP 2 LAST SEC 1
J 0
(6325 4225);
DISPLAY 0.680851 (6325 4225);
PAINT MONO (6325 4225);
DISPLAY INVISIBLE (6325 4225);
FORCEPROP 1 LASTPIN (6275 4025) $PN 1
J 0
(6287 4037);
DISPLAY 0.638298 (6287 4037);
PAINT MONO (6287 4037);
FORCEPROP 1 LASTPIN (6475 4025) $PN 2
J 0
(6437 4037);
DISPLAY 0.638298 (6437 4037);
PAINT MONO (6437 4037);
FORCEPROP 1 LAST PACK_TYPE 0402LF
J 0
(6700 4025);
DISPLAY 0.510638 (6700 4025);
FORCEPROP 1 LAST WATTAGE 1/16W
J 2
(6500 4100);
DISPLAY 0.510638 (6500 4100);
FORCEPROP 1 LAST MATERIAL CHIP
J 0
(6250 4100);
DISPLAY 0.510638 (6250 4100);
FORCEPROP 1 LAST VALUE 200
J 2
(6600 4025);
DISPLAY 0.510638 (6600 4025);
FORCEPROP 1 LAST TOLERANCE 1%
J 0
(6625 4025);
DISPLAY 0.510638 (6625 4025);
FORCEPROP 2 LAST SEC_TYPE 0402LF
J 0
(6325 4225);
DISPLAY 0.680851 (6325 4225);
DISPLAY INVISIBLE (6325 4225);
FORCEPROP 2 LAST CDS_LIB pure_quanta
J 0
(6375 4025);
DISPLAY INVISIBLE (6375 4025);
FORCEPROP 1 LAST PATH I171
J 0
(6325 4175);
DISPLAY 0.978723 (6325 4175);
PAINT WHITE (6325 4175);
DISPLAY INVISIBLE (6325 4175);
FORCEPROP 1 LAST PART_NUMBER CS12002FB06
J 0
(6250 4075);
DISPLAY 0.510638 (6250 4075);
DISPLAY INVISIBLE (6250 4075);
FORCEADD Q_CAP..1
(7150 -300);
FORCEPROP 1 LAST LOCATION C1839
J 0
(7200 -200);
DISPLAY 0.978723 (7200 -200);
FORCEPROP 0 LAST $SEC 1
J 0
(7200 -150);
DISPLAY 0.680851 (7200 -150);
PAINT MONO (7200 -150);
DISPLAY INVISIBLE (7200 -150);
FORCEPROP 0 LAST CDS_SEC 1
J 0
(7200 -150);
DISPLAY 1.021277 (7200 -150);
DISPLAY INVISIBLE (7200 -150);
FORCEPROP 1 LASTPIN (7150 -200) $PN 1
J 0
(7160 -220);
DISPLAY 0.787234 (7160 -220);
PAINT MONO (7160 -220);
FORCEPROP 1 LASTPIN (7150 -400) $PN 2
J 0
(7160 -420);
DISPLAY 0.787234 (7160 -420);
PAINT MONO (7160 -420);
FORCEPROP 1 LAST VALUE 0.1UF
J 0
(7200 -250);
DISPLAY 0.638298 (7200 -250);
FORCEPROP 1 LAST PACK_TYPE 0402
J 0
(7200 -450);
DISPLAY 0.638298 (7200 -450);
FORCEPROP 1 LAST TOLERANCE 10%
J 0
(7200 -350);
DISPLAY 0.638298 (7200 -350);
FORCEPROP 1 LAST MATERIAL X7R
J 0
(7200 -400);
DISPLAY 0.638298 (7200 -400);
FORCEPROP 1 LAST VOLTAGE 25V
J 0
(7200 -300);
DISPLAY 0.638298 (7200 -300);
FORCEPROP 2 LAST CDS_LIB pure_quanta
J 0
(7150 -300);
DISPLAY INVISIBLE (7150 -300);
FORCEPROP 1 LAST PATH I18
J 0
(7200 -150);
DISPLAY 0.978723 (7200 -150);
PAINT WHITE (7200 -150);
DISPLAY INVISIBLE (7200 -150);
FORCEPROP 1 LAST PART_NUMBER CH4104K1B00
J 0
(7200 -450);
DISPLAY 0.808511 (7200 -450);
DISPLAY INVISIBLE (7200 -450);
FORCEADD UNIVERSAL_GND..1
(7400 -625);
FORCEPROP 3 LASTPIN (7400 -575) SIG_NAME GND\g
J 0
(7410 -565);
DISPLAY 0.659574 (7410 -565);
PAINT MONO (7410 -565);
DISPLAY INVISIBLE (7410 -565);
FORCEPROP 2 LAST ROOM IO_SLOT
J 1
(7175 -550);
DISPLAY 0.744681 (7175 -550);
FORCEPROP 2 LAST CDS_LIB pure_quanta_power
J 0
(7400 -625);
PAINT MONO (7400 -625);
DISPLAY INVISIBLE (7400 -625);
FORCEPROP 1 LAST HDL_POWER GND
J 1
(7425 -700);
DISPLAY 0.872340 (7425 -700);
PAINT GREEN (7425 -700);
DISPLAY INVISIBLE (7425 -700);
FORCEPROP 1 LAST PATH I19
J 0
(7475 -625);
DISPLAY 0.872340 (7475 -625);
PAINT AQUA (7475 -625);
DISPLAY INVISIBLE (7475 -625);
FORCEADD Q_RES..2
(275 -225);
FORCEPROP 1 LAST LOCATION R3163
J 0
(320 -100);
DISPLAY 0.978723 (320 -100);
FORCEPROP 2 LAST $SEC 1
J 0
(325 0);
DISPLAY 0.680851 (325 0);
PAINT MONO (325 0);
DISPLAY INVISIBLE (325 0);
FORCEPROP 2 LAST CDS_SEC 1
J 0
(325 0);
DISPLAY 1.021277 (325 0);
DISPLAY INVISIBLE (325 0);
FORCEPROP 1 LASTPIN (275 -125) $PN 1
J 0
(280 -163);
DISPLAY 0.787234 (280 -163);
FORCEPROP 1 LASTPIN (275 -325) $PN 2
J 0
(280 -315);
DISPLAY 0.787234 (280 -315);
FORCEPROP 1 LAST WATTAGE 1/16W
J 0
(315 -250);
DISPLAY 0.787234 (315 -250);
FORCEPROP 1 LAST MATERIAL EMPTY
J 0
(315 -300);
DISPLAY 0.787234 (315 -300);
FORCEPROP 1 LAST PACK_TYPE 0402LF
J 0
(315 -400);
DISPLAY 0.787234 (315 -400);
FORCEPROP 1 LAST TOLERANCE 1%
J 0
(320 -200);
DISPLAY 0.787234 (320 -200);
FORCEPROP 1 LAST VALUE 4.7K
J 0
(320 -150);
DISPLAY 0.787234 (320 -150);
FORCEPROP 2 LAST CDS_LIB pure_quanta
J 0
(275 -225);
PAINT MONO (275 -225);
DISPLAY INVISIBLE (275 -225);
FORCEPROP 1 LAST PATH I2
J 0
(325 -50);
DISPLAY 0.978723 (325 -50);
PAINT WHITE (325 -50);
DISPLAY INVISIBLE (325 -50);
FORCEPROP 1 LAST PART_NUMBER CS24702FB06
J 0
(315 -350);
DISPLAY 0.787234 (315 -350);
DISPLAY INVISIBLE (315 -350);
FORCEADD Q_CAP..1
(7400 -300);
FORCEPROP 1 LAST LOCATION C1834
J 0
(7450 -200);
DISPLAY 0.787234 (7450 -200);
FORCEPROP 2 LAST $SEC 1
J 0
(7450 -100);
DISPLAY 0.680851 (7450 -100);
PAINT MONO (7450 -100);
DISPLAY INVISIBLE (7450 -100);
FORCEPROP 2 LAST CDS_SEC 1
J 0
(7450 -100);
DISPLAY 1.021277 (7450 -100);
DISPLAY INVISIBLE (7450 -100);
FORCEPROP 1 LASTPIN (7400 -200) $PN 1
J 0
(7410 -220);
DISPLAY 0.787234 (7410 -220);
FORCEPROP 1 LASTPIN (7400 -400) $PN 2
J 0
(7410 -420);
DISPLAY 0.787234 (7410 -420);
FORCEPROP 1 LAST VOLTAGE 25V
J 0
(7450 -300);
DISPLAY 0.638298 (7450 -300);
FORCEPROP 1 LAST VALUE 0.1UF
J 0
(7450 -250);
DISPLAY 0.638298 (7450 -250);
FORCEPROP 1 LAST TOLERANCE 10%
J 0
(7450 -350);
DISPLAY 0.638298 (7450 -350);
FORCEPROP 1 LAST MATERIAL X7R
J 0
(7450 -400);
DISPLAY 0.638298 (7450 -400);
FORCEPROP 1 LAST PACK_TYPE 0402
J 0
(7450 -450);
DISPLAY 0.638298 (7450 -450);
FORCEPROP 2 LAST CDS_LIB pure_quanta
J 0
(7400 -300);
PAINT MONO (7400 -300);
DISPLAY INVISIBLE (7400 -300);
FORCEPROP 1 LAST PATH I20
J 0
(7450 -150);
DISPLAY 0.978723 (7450 -150);
PAINT WHITE (7450 -150);
DISPLAY INVISIBLE (7450 -150);
FORCEPROP 1 LAST PART_NUMBER CH4104K1B00
J 0
(7450 -500);
DISPLAY 0.638298 (7450 -500);
DISPLAY INVISIBLE (7450 -500);
FORCEADD Q_CAP..1
(7900 -300);
FORCEPROP 1 LAST LOCATION C1835
J 0
(7950 -200);
DISPLAY 0.787234 (7950 -200);
FORCEPROP 2 LAST $SEC 1
J 0
(7950 -100);
DISPLAY 0.680851 (7950 -100);
PAINT MONO (7950 -100);
DISPLAY INVISIBLE (7950 -100);
FORCEPROP 2 LAST CDS_SEC 1
J 0
(7950 -100);
DISPLAY 1.021277 (7950 -100);
DISPLAY INVISIBLE (7950 -100);
FORCEPROP 1 LASTPIN (7900 -200) $PN 1
J 0
(7910 -220);
DISPLAY 0.787234 (7910 -220);
FORCEPROP 1 LASTPIN (7900 -400) $PN 2
J 0
(7910 -420);
DISPLAY 0.787234 (7910 -420);
FORCEPROP 1 LAST VOLTAGE 25V
J 0
(7950 -300);
DISPLAY 0.638298 (7950 -300);
FORCEPROP 1 LAST TOLERANCE 10%
J 0
(7950 -350);
DISPLAY 0.638298 (7950 -350);
FORCEPROP 1 LAST PACK_TYPE 0402
J 0
(7950 -450);
DISPLAY 0.638298 (7950 -450);
FORCEPROP 1 LAST MATERIAL X7R
J 0
(7950 -400);
DISPLAY 0.638298 (7950 -400);
FORCEPROP 1 LAST VALUE 0.1UF
J 0
(7950 -250);
DISPLAY 0.638298 (7950 -250);
FORCEPROP 2 LAST CDS_LIB pure_quanta
J 0
(7900 -300);
PAINT MONO (7900 -300);
DISPLAY INVISIBLE (7900 -300);
FORCEPROP 1 LAST PATH I21
J 0
(7950 -150);
DISPLAY 0.978723 (7950 -150);
PAINT WHITE (7950 -150);
DISPLAY INVISIBLE (7950 -150);
FORCEPROP 1 LAST PART_NUMBER CH4104K1B00
J 0
(7950 -450);
DISPLAY 0.808511 (7950 -450);
DISPLAY INVISIBLE (7950 -450);
FORCEADD Q_CAP..1
(8150 -300);
FORCEPROP 1 LAST LOCATION C1836
J 0
(8200 -200);
DISPLAY 0.787234 (8200 -200);
FORCEPROP 2 LAST $SEC 1
J 0
(8200 -100);
DISPLAY 0.680851 (8200 -100);
PAINT MONO (8200 -100);
DISPLAY INVISIBLE (8200 -100);
FORCEPROP 2 LAST CDS_SEC 1
J 0
(8200 -100);
DISPLAY 1.021277 (8200 -100);
DISPLAY INVISIBLE (8200 -100);
FORCEPROP 1 LASTPIN (8150 -200) $PN 1
J 0
(8160 -220);
DISPLAY 0.787234 (8160 -220);
FORCEPROP 1 LASTPIN (8150 -400) $PN 2
J 0
(8160 -420);
DISPLAY 0.787234 (8160 -420);
FORCEPROP 1 LAST MATERIAL X7R
J 0
(8200 -400);
DISPLAY 0.638298 (8200 -400);
FORCEPROP 1 LAST TOLERANCE 10%
J 0
(8200 -350);
DISPLAY 0.638298 (8200 -350);
FORCEPROP 1 LAST VALUE 0.1UF
J 0
(8200 -250);
DISPLAY 0.638298 (8200 -250);
FORCEPROP 1 LAST PACK_TYPE 0402
J 0
(8200 -450);
DISPLAY 0.638298 (8200 -450);
FORCEPROP 1 LAST VOLTAGE 25V
J 0
(8200 -300);
DISPLAY 0.638298 (8200 -300);
FORCEPROP 2 LAST CDS_LIB pure_quanta
J 0
(8150 -300);
PAINT MONO (8150 -300);
DISPLAY INVISIBLE (8150 -300);
FORCEPROP 1 LAST PATH I22
J 0
(8200 -150);
DISPLAY 0.978723 (8200 -150);
PAINT WHITE (8200 -150);
DISPLAY INVISIBLE (8200 -150);
FORCEPROP 1 LAST PART_NUMBER CH4104K1B00
J 0
(8200 -450);
DISPLAY 0.808511 (8200 -450);
DISPLAY INVISIBLE (8200 -450);
FORCEADD Q_CAP..1
(8425 -300);
FORCEPROP 1 LAST LOCATION C1837
J 0
(8475 -200);
DISPLAY 0.787234 (8475 -200);
FORCEPROP 2 LAST $SEC 1
J 0
(8475 -100);
DISPLAY 0.680851 (8475 -100);
PAINT MONO (8475 -100);
DISPLAY INVISIBLE (8475 -100);
FORCEPROP 2 LAST CDS_SEC 1
J 0
(8475 -100);
DISPLAY 1.021277 (8475 -100);
DISPLAY INVISIBLE (8475 -100);
FORCEPROP 1 LASTPIN (8425 -200) $PN 1
J 0
(8435 -220);
DISPLAY 0.787234 (8435 -220);
FORCEPROP 1 LASTPIN (8425 -400) $PN 2
J 0
(8435 -420);
DISPLAY 0.787234 (8435 -420);
FORCEPROP 1 LAST PACK_TYPE 0402
J 0
(8475 -450);
DISPLAY 0.638298 (8475 -450);
FORCEPROP 1 LAST MATERIAL X7R
J 0
(8475 -400);
DISPLAY 0.638298 (8475 -400);
FORCEPROP 1 LAST TOLERANCE 10%
J 0
(8475 -350);
DISPLAY 0.638298 (8475 -350);
FORCEPROP 1 LAST VOLTAGE 25V
J 0
(8475 -300);
DISPLAY 0.638298 (8475 -300);
FORCEPROP 1 LAST VALUE 0.1UF
J 0
(8475 -250);
DISPLAY 0.638298 (8475 -250);
FORCEPROP 2 LAST CDS_LIB pure_quanta
J 0
(8425 -300);
PAINT MONO (8425 -300);
DISPLAY INVISIBLE (8425 -300);
FORCEPROP 1 LAST PATH I23
J 0
(8475 -150);
DISPLAY 0.978723 (8475 -150);
PAINT WHITE (8475 -150);
DISPLAY INVISIBLE (8475 -150);
FORCEPROP 1 LAST PART_NUMBER CH4104K1B00
J 0
(8475 -450);
DISPLAY 0.808511 (8475 -450);
DISPLAY INVISIBLE (8475 -450);
FORCEADD Q_CAP..1
(8700 -300);
FORCEPROP 1 LAST LOCATION C1838
J 0
(8750 -200);
DISPLAY 0.787234 (8750 -200);
FORCEPROP 2 LAST $SEC 1
J 0
(8750 -100);
DISPLAY 0.680851 (8750 -100);
PAINT MONO (8750 -100);
DISPLAY INVISIBLE (8750 -100);
FORCEPROP 2 LAST CDS_SEC 1
J 0
(8750 -100);
DISPLAY 1.021277 (8750 -100);
DISPLAY INVISIBLE (8750 -100);
FORCEPROP 1 LASTPIN (8700 -200) $PN 1
J 0
(8710 -220);
DISPLAY 0.787234 (8710 -220);
FORCEPROP 1 LASTPIN (8700 -400) $PN 2
J 0
(8710 -420);
DISPLAY 0.787234 (8710 -420);
FORCEPROP 1 LAST VOLTAGE 25V
J 0
(8750 -300);
DISPLAY 0.638298 (8750 -300);
FORCEPROP 1 LAST TOLERANCE 10%
J 0
(8750 -350);
DISPLAY 0.638298 (8750 -350);
FORCEPROP 1 LAST MATERIAL X7R
J 0
(8750 -400);
DISPLAY 0.638298 (8750 -400);
FORCEPROP 1 LAST VALUE 0.1UF
J 0
(8750 -250);
DISPLAY 0.638298 (8750 -250);
FORCEPROP 1 LAST PACK_TYPE 0402
J 0
(8750 -450);
DISPLAY 0.638298 (8750 -450);
FORCEPROP 2 LAST CDS_LIB pure_quanta
J 0
(8700 -300);
PAINT MONO (8700 -300);
DISPLAY INVISIBLE (8700 -300);
FORCEPROP 1 LAST PATH I24
J 0
(8750 -150);
DISPLAY 0.978723 (8750 -150);
PAINT WHITE (8750 -150);
DISPLAY INVISIBLE (8750 -150);
FORCEPROP 1 LAST PART_NUMBER CH4104K1B00
J 0
(8750 -500);
DISPLAY 0.638298 (8750 -500);
DISPLAY INVISIBLE (8750 -500);
FORCEADD UNIVERSAL_GND..1
(8700 -625);
FORCEPROP 3 LASTPIN (8700 -575) SIG_NAME GND\g
J 0
(8710 -565);
DISPLAY 0.659574 (8710 -565);
PAINT MONO (8710 -565);
DISPLAY INVISIBLE (8710 -565);
FORCEPROP 2 LAST ROOM IO_SLOT
J 1
(8475 -550);
DISPLAY 0.744681 (8475 -550);
FORCEPROP 2 LAST CDS_LIB pure_quanta_power
J 0
(8700 -625);
PAINT MONO (8700 -625);
DISPLAY INVISIBLE (8700 -625);
FORCEPROP 1 LAST HDL_POWER GND
J 1
(8725 -700);
DISPLAY 0.872340 (8725 -700);
PAINT GREEN (8725 -700);
DISPLAY INVISIBLE (8725 -700);
FORCEPROP 1 LAST PATH I25
J 0
(8775 -625);
DISPLAY 0.872340 (8775 -625);
PAINT AQUA (8775 -625);
DISPLAY INVISIBLE (8775 -625);
FORCEADD Q_RES..2
(275 300);
FORCEPROP 1 LAST LOCATION R3162
J 0
(320 425);
DISPLAY 0.978723 (320 425);
FORCEPROP 2 LAST $SEC 1
J 0
(325 525);
DISPLAY 0.680851 (325 525);
PAINT MONO (325 525);
DISPLAY INVISIBLE (325 525);
FORCEPROP 2 LAST CDS_SEC 1
J 0
(325 525);
DISPLAY 1.021277 (325 525);
DISPLAY INVISIBLE (325 525);
FORCEPROP 1 LASTPIN (275 400) $PN 1
J 0
(280 362);
DISPLAY 0.787234 (280 362);
FORCEPROP 1 LASTPIN (275 200) $PN 2
J 0
(280 210);
DISPLAY 0.787234 (280 210);
FORCEPROP 1 LAST WATTAGE 1/16W
J 0
(315 275);
DISPLAY 0.787234 (315 275);
FORCEPROP 1 LAST PACK_TYPE 0402LF
J 0
(315 125);
DISPLAY 0.787234 (315 125);
FORCEPROP 1 LAST TOLERANCE 1%
J 0
(320 325);
DISPLAY 0.787234 (320 325);
FORCEPROP 1 LAST MATERIAL CHIP
J 0
(315 225);
DISPLAY 0.787234 (315 225);
FORCEPROP 1 LAST VALUE 4.7K
J 0
(320 375);
DISPLAY 0.787234 (320 375);
FORCEPROP 2 LAST CDS_LIB pure_quanta
J 0
(275 300);
PAINT MONO (275 300);
DISPLAY INVISIBLE (275 300);
FORCEPROP 1 LAST PATH I26
J 0
(325 475);
DISPLAY 0.978723 (325 475);
PAINT WHITE (325 475);
DISPLAY INVISIBLE (325 475);
FORCEPROP 1 LAST PART_NUMBER CS24702FB06
J 0
(315 175);
DISPLAY 0.787234 (315 175);
DISPLAY INVISIBLE (315 175);
FORCEADD UNIVERSAL_POWER..1
(275 600);
FORCEPROP 3 LASTPIN (275 550) SIG_NAME P3V3_OCP_V3_2\g
J 0
(285 560);
DISPLAY 0.659574 (285 560);
PAINT MONO (285 560);
DISPLAY INVISIBLE (285 560);
FORCEPROP 1 LAST HDL_POWER P3V3_OCP_V3_2
J 1
(275 650);
DISPLAY 0.872340 (275 650);
PAINT GREEN (275 650);
FORCEPROP 2 LAST CDS_LIB pure_quanta_power
J 0
(275 600);
PAINT MONO (275 600);
DISPLAY INVISIBLE (275 600);
FORCEPROP 1 LAST PATH I27
J 0
(325 625);
DISPLAY 0.872340 (325 625);
PAINT AQUA (325 625);
DISPLAY INVISIBLE (325 625);
FORCEADD Q_RES..2
(750 300);
FORCEPROP 1 LAST LOCATION R3166
J 0
(795 425);
DISPLAY 0.978723 (795 425);
FORCEPROP 2 LAST $SEC 1
J 0
(800 525);
DISPLAY 0.680851 (800 525);
PAINT MONO (800 525);
DISPLAY INVISIBLE (800 525);
FORCEPROP 2 LAST CDS_SEC 1
J 0
(800 525);
DISPLAY 1.021277 (800 525);
DISPLAY INVISIBLE (800 525);
FORCEPROP 1 LASTPIN (750 400) $PN 1
J 0
(755 362);
DISPLAY 0.787234 (755 362);
FORCEPROP 1 LASTPIN (750 200) $PN 2
J 0
(755 210);
DISPLAY 0.787234 (755 210);
FORCEPROP 1 LAST VALUE 4.7K
J 0
(795 375);
DISPLAY 0.787234 (795 375);
FORCEPROP 1 LAST TOLERANCE 1%
J 0
(795 325);
DISPLAY 0.787234 (795 325);
FORCEPROP 1 LAST PACK_TYPE 0402LF
J 0
(790 125);
DISPLAY 0.787234 (790 125);
FORCEPROP 1 LAST MATERIAL EMPTY
J 0
(790 225);
DISPLAY 0.787234 (790 225);
FORCEPROP 1 LAST WATTAGE 1/16W
J 0
(790 275);
DISPLAY 0.787234 (790 275);
FORCEPROP 2 LAST CDS_LIB pure_quanta
J 0
(750 300);
PAINT MONO (750 300);
DISPLAY INVISIBLE (750 300);
FORCEPROP 1 LAST PATH I28
J 0
(800 475);
DISPLAY 0.978723 (800 475);
PAINT WHITE (800 475);
DISPLAY INVISIBLE (800 475);
FORCEPROP 1 LAST PART_NUMBER CS24702FB06
J 0
(790 175);
DISPLAY 0.787234 (790 175);
DISPLAY INVISIBLE (790 175);
FORCEADD OFFPAGE..2
(1350 0);
FORCEPROP 2 LAST $XR0 137 
J 0
(1539 0);
DISPLAY 0.638298 (1539 0);
PAINT MONO (1539 0);
FORCEPROP 2 LAST CDS_LIB standard
J 0
(1350 0);
PAINT MONO (1350 0);
DISPLAY INVISIBLE (1350 0);
FORCEPROP 1 LAST OFFPAGE TRUE
J 0
(1675 -125);
DISPLAY 0.872340 (1675 -125);
PAINT GREEN (1675 -125);
DISPLAY INVISIBLE (1675 -125);
FORCEPROP 1 LAST COMMENT_BODY TRUE
J 0
(1305 -95);
DISPLAY 0.872340 (1305 -95);
PAINT GREEN (1305 -95);
DISPLAY INVISIBLE (1305 -95);
FORCEPROP 2 LAST PATH I29
J 0
(1550 50);
DISPLAY 0.680851 (1550 50);
DISPLAY INVISIBLE (1550 50);
FORCEADD Q_RES..2
(750 -225);
FORCEPROP 1 LAST LOCATION R3167
J 0
(795 -100);
DISPLAY 0.978723 (795 -100);
FORCEPROP 2 LAST $SEC 1
J 0
(800 0);
DISPLAY 0.680851 (800 0);
PAINT MONO (800 0);
DISPLAY INVISIBLE (800 0);
FORCEPROP 2 LAST CDS_SEC 1
J 0
(800 0);
DISPLAY 1.021277 (800 0);
DISPLAY INVISIBLE (800 0);
FORCEPROP 1 LASTPIN (750 -125) $PN 1
J 0
(755 -163);
DISPLAY 0.787234 (755 -163);
FORCEPROP 1 LASTPIN (750 -325) $PN 2
J 0
(755 -315);
DISPLAY 0.787234 (755 -315);
FORCEPROP 1 LAST PACK_TYPE 0402LF
J 0
(790 -400);
DISPLAY 0.787234 (790 -400);
FORCEPROP 1 LAST VALUE 4.7K
J 0
(795 -150);
DISPLAY 0.787234 (795 -150);
FORCEPROP 1 LAST TOLERANCE 1%
J 0
(795 -200);
DISPLAY 0.787234 (795 -200);
FORCEPROP 1 LAST WATTAGE 1/16W
J 0
(790 -250);
DISPLAY 0.787234 (790 -250);
FORCEPROP 1 LAST MATERIAL CHIP
J 0
(790 -300);
DISPLAY 0.787234 (790 -300);
FORCEPROP 2 LAST CDS_LIB pure_quanta
J 0
(750 -225);
PAINT MONO (750 -225);
DISPLAY INVISIBLE (750 -225);
FORCEPROP 1 LAST PATH I3
J 0
(800 -50);
DISPLAY 0.978723 (800 -50);
PAINT WHITE (800 -50);
DISPLAY INVISIBLE (800 -50);
FORCEPROP 1 LAST PART_NUMBER CS24702FB06
J 0
(790 -350);
DISPLAY 0.787234 (790 -350);
DISPLAY INVISIBLE (790 -350);
FORCEADD OFFPAGE..2
(1350 50);
FORCEPROP 2 LAST $XR0 137 
J 0
(1539 50);
DISPLAY 0.638298 (1539 50);
PAINT MONO (1539 50);
FORCEPROP 2 LAST CDS_LIB standard
J 0
(1350 50);
PAINT MONO (1350 50);
DISPLAY INVISIBLE (1350 50);
FORCEPROP 1 LAST OFFPAGE TRUE
J 0
(1675 -75);
DISPLAY 0.872340 (1675 -75);
PAINT GREEN (1675 -75);
DISPLAY INVISIBLE (1675 -75);
FORCEPROP 1 LAST COMMENT_BODY TRUE
J 0
(1305 -45);
DISPLAY 0.872340 (1305 -45);
PAINT GREEN (1305 -45);
DISPLAY INVISIBLE (1305 -45);
FORCEPROP 2 LAST PATH I30
J 0
(1550 100);
DISPLAY 0.680851 (1550 100);
DISPLAY INVISIBLE (1550 100);
FORCEADD UNIVERSAL_GND..1
(300 2400);
FORCEPROP 3 LASTPIN (300 2450) SIG_NAME GND\g
J 0
(310 2460);
DISPLAY 0.659574 (310 2460);
PAINT MONO (310 2460);
DISPLAY INVISIBLE (310 2460);
FORCEPROP 2 LAST CDS_LIB pure_quanta_power
J 0
(300 2400);
DISPLAY INVISIBLE (300 2400);
FORCEPROP 1 LAST HDL_POWER GND
J 1
(325 2325);
DISPLAY 0.872340 (325 2325);
PAINT GREEN (325 2325);
DISPLAY INVISIBLE (325 2325);
FORCEPROP 1 LAST PATH I31
J 0
(375 2400);
DISPLAY 0.872340 (375 2400);
PAINT AQUA (375 2400);
DISPLAY INVISIBLE (375 2400);
FORCEADD Q_RES..1
(725 2750);
FORCEPROP 1 LAST LOCATION R3165
J 0
(450 2750);
DISPLAY 0.787234 (450 2750);
FORCEPROP 0 LAST $SEC 1
J 0
(450 2800);
DISPLAY 0.680851 (450 2800);
PAINT MONO (450 2800);
DISPLAY INVISIBLE (450 2800);
FORCEPROP 0 LAST CDS_SEC 1
J 0
(450 2800);
DISPLAY 1.021277 (450 2800);
DISPLAY INVISIBLE (450 2800);
FORCEPROP 1 LASTPIN (625 2750) $PN 1
J 0
(637 2762);
DISPLAY 0.787234 (637 2762);
PAINT MONO (637 2762);
FORCEPROP 1 LASTPIN (825 2750) $PN 2
J 0
(787 2762);
DISPLAY 0.787234 (787 2762);
PAINT MONO (787 2762);
FORCEPROP 1 LAST VALUE 10K
J 2
(900 2750);
DISPLAY 0.510638 (900 2750);
FORCEPROP 1 LAST MATERIAL CHIP
J 0
(1000 2750);
DISPLAY 0.510638 (1000 2750);
FORCEPROP 1 LAST TOLERANCE 1%
J 0
(925 2750);
DISPLAY 0.510638 (925 2750);
FORCEPROP 1 LAST WATTAGE 1/16W
J 2
(925 2875);
DISPLAY 0.510638 (925 2875);
DISPLAY INVISIBLE (925 2875);
FORCEPROP 1 LAST PACK_TYPE 0402LF
J 0
(550 2875);
DISPLAY 0.510638 (550 2875);
DISPLAY INVISIBLE (550 2875);
FORCEPROP 2 LAST CDS_LIB pure_quanta
J 0
(725 2750);
DISPLAY INVISIBLE (725 2750);
FORCEPROP 1 LAST PATH I32
J 0
(675 2900);
DISPLAY 0.978723 (675 2900);
PAINT WHITE (675 2900);
DISPLAY INVISIBLE (675 2900);
FORCEPROP 1 LAST PART_NUMBER CS31002FB08
J 0
(550 2825);
DISPLAY 0.510638 (550 2825);
DISPLAY INVISIBLE (550 2825);
FORCEADD Q_RES..1
(775 2550);
FORCEPROP 1 LAST LOCATION R8413
J 0
(500 2550);
DISPLAY 0.787234 (500 2550);
FORCEPROP 0 LAST $SEC 1
J 0
(975 2675);
DISPLAY 0.680851 (975 2675);
PAINT MONO (975 2675);
DISPLAY INVISIBLE (975 2675);
FORCEPROP 0 LAST CDS_SEC 1
J 0
(975 2675);
DISPLAY 1.021277 (975 2675);
DISPLAY INVISIBLE (975 2675);
FORCEPROP 1 LASTPIN (675 2550) $PN 1
J 0
(687 2562);
DISPLAY 0.787234 (687 2562);
PAINT MONO (687 2562);
FORCEPROP 1 LASTPIN (875 2550) $PN 2
J 0
(837 2562);
DISPLAY 0.787234 (837 2562);
PAINT MONO (837 2562);
FORCEPROP 1 LAST VALUE 100K
J 2
(975 2550);
DISPLAY 0.510638 (975 2550);
FORCEPROP 1 LAST TOLERANCE 1%
J 0
(1000 2550);
DISPLAY 0.510638 (1000 2550);
FORCEPROP 1 LAST MATERIAL CHIP
J 0
(1100 2550);
DISPLAY 0.510638 (1100 2550);
FORCEPROP 1 LAST PACK_TYPE 0402LF
J 0
(600 2650);
DISPLAY 0.510638 (600 2650);
FORCEPROP 1 LAST WATTAGE 1/16W
J 2
(975 2650);
DISPLAY 0.510638 (975 2650);
FORCEPROP 2 LAST CDS_LIB pure_quanta
J 0
(775 2550);
DISPLAY INVISIBLE (775 2550);
FORCEPROP 1 LAST PATH I33
J 0
(725 2700);
DISPLAY 0.978723 (725 2700);
PAINT WHITE (725 2700);
DISPLAY INVISIBLE (725 2700);
FORCEPROP 1 LAST PART_NUMBER CS41002FB09
J 0
(600 2600);
DISPLAY 0.510638 (600 2600);
DISPLAY INVISIBLE (600 2600);
FORCEADD Q_RES..1
(725 2850);
FORCEPROP 1 LAST LOCATION R3164
J 0
(450 2850);
DISPLAY 0.787234 (450 2850);
FORCEPROP 0 LAST $SEC 1
J 0
(925 3000);
DISPLAY 0.680851 (925 3000);
PAINT MONO (925 3000);
DISPLAY INVISIBLE (925 3000);
FORCEPROP 0 LAST CDS_SEC 1
J 0
(925 3000);
DISPLAY 1.021277 (925 3000);
DISPLAY INVISIBLE (925 3000);
FORCEPROP 1 LASTPIN (625 2850) $PN 1
J 0
(637 2862);
DISPLAY 0.787234 (637 2862);
PAINT MONO (637 2862);
FORCEPROP 1 LASTPIN (825 2850) $PN 2
J 0
(787 2862);
DISPLAY 0.787234 (787 2862);
PAINT MONO (787 2862);
FORCEPROP 1 LAST MATERIAL CHIP
J 0
(1000 2850);
DISPLAY 0.510638 (1000 2850);
FORCEPROP 1 LAST PACK_TYPE 0402LF
J 0
(550 2975);
DISPLAY 0.510638 (550 2975);
FORCEPROP 1 LAST VALUE 10K
J 2
(900 2850);
DISPLAY 0.510638 (900 2850);
FORCEPROP 1 LAST TOLERANCE 1%
J 0
(925 2850);
DISPLAY 0.510638 (925 2850);
FORCEPROP 1 LAST WATTAGE 1/16W
J 2
(925 2975);
DISPLAY 0.510638 (925 2975);
FORCEPROP 2 LAST CDS_LIB pure_quanta
J 0
(725 2850);
DISPLAY INVISIBLE (725 2850);
FORCEPROP 1 LAST PATH I34
J 0
(675 3000);
DISPLAY 0.978723 (675 3000);
PAINT WHITE (675 3000);
DISPLAY INVISIBLE (675 3000);
FORCEPROP 1 LAST PART_NUMBER CS31002FB08
J 0
(550 2925);
DISPLAY 0.510638 (550 2925);
DISPLAY INVISIBLE (550 2925);
FORCEADD OFFPAGE..1
(1000 3775);
FORCEPROP 2 LAST $XR3 139 
J 0
(358 3775);
DISPLAY 0.638298 (358 3775);
PAINT MONO (358 3775);
FORCEPROP 2 LAST $XR2 138 
J 0
(478 3775);
DISPLAY 0.638298 (478 3775);
PAINT MONO (478 3775);
FORCEPROP 2 LAST $XR1 142 
J 0
(598 3775);
DISPLAY 0.638298 (598 3775);
PAINT MONO (598 3775);
FORCEPROP 2 LAST $XR0 137 
J 0
(718 3775);
DISPLAY 0.638298 (718 3775);
PAINT MONO (718 3775);
FORCEPROP 2 LAST CDS_LIB standard
J 0
(1000 3775);
PAINT MONO (1000 3775);
DISPLAY INVISIBLE (1000 3775);
FORCEPROP 1 LAST OFFPAGE TRUE
J 0
(1325 3650);
DISPLAY 0.872340 (1325 3650);
PAINT GREEN (1325 3650);
DISPLAY INVISIBLE (1325 3650);
FORCEPROP 1 LAST COMMENT_BODY TRUE
J 0
(1125 3675);
DISPLAY 0.872340 (1125 3675);
PAINT GREEN (1125 3675);
DISPLAY INVISIBLE (1125 3675);
FORCEPROP 2 LAST PATH I35
J 0
(725 3825);
DISPLAY 0.680851 (725 3825);
DISPLAY INVISIBLE (725 3825);
FORCEADD OFFPAGE..1
(1000 3875);
FORCEPROP 2 LAST $XR0 139 
J 0
(718 3875);
DISPLAY 0.638298 (718 3875);
PAINT MONO (718 3875);
FORCEPROP 2 LAST CDS_LIB standard
J 0
(1000 3875);
PAINT MONO (1000 3875);
DISPLAY INVISIBLE (1000 3875);
FORCEPROP 1 LAST OFFPAGE TRUE
J 0
(1325 3750);
DISPLAY 0.872340 (1325 3750);
PAINT GREEN (1325 3750);
DISPLAY INVISIBLE (1325 3750);
FORCEPROP 1 LAST COMMENT_BODY TRUE
J 0
(1125 3775);
DISPLAY 0.872340 (1125 3775);
PAINT GREEN (1125 3775);
DISPLAY INVISIBLE (1125 3775);
FORCEPROP 2 LAST PATH I36
J 0
(725 3925);
DISPLAY 0.680851 (725 3925);
DISPLAY INVISIBLE (725 3925);
FORCEADD OFFPAGE..1
(1000 3975);
FORCEPROP 2 LAST $XR0 138 
J 0
(718 3975);
DISPLAY 0.638298 (718 3975);
PAINT MONO (718 3975);
FORCEPROP 2 LAST CDS_LIB standard
J 0
(1000 3975);
PAINT MONO (1000 3975);
DISPLAY INVISIBLE (1000 3975);
FORCEPROP 1 LAST OFFPAGE TRUE
J 0
(1325 3850);
DISPLAY 0.872340 (1325 3850);
PAINT GREEN (1325 3850);
DISPLAY INVISIBLE (1325 3850);
FORCEPROP 1 LAST COMMENT_BODY TRUE
J 0
(1125 3875);
DISPLAY 0.872340 (1125 3875);
PAINT GREEN (1125 3875);
DISPLAY INVISIBLE (1125 3875);
FORCEPROP 2 LAST PATH I37
J 0
(725 4025);
DISPLAY 0.680851 (725 4025);
DISPLAY INVISIBLE (725 4025);
FORCEADD OFFPAGE..1
(1000 3925);
FORCEPROP 2 LAST $XR0 138 
J 0
(718 3925);
DISPLAY 0.638298 (718 3925);
PAINT MONO (718 3925);
FORCEPROP 2 LAST CDS_LIB standard
J 0
(1000 3925);
PAINT MONO (1000 3925);
DISPLAY INVISIBLE (1000 3925);
FORCEPROP 1 LAST OFFPAGE TRUE
J 0
(1325 3800);
DISPLAY 0.872340 (1325 3800);
PAINT GREEN (1325 3800);
DISPLAY INVISIBLE (1325 3800);
FORCEPROP 1 LAST COMMENT_BODY TRUE
J 0
(1125 3825);
DISPLAY 0.872340 (1125 3825);
PAINT GREEN (1125 3825);
DISPLAY INVISIBLE (1125 3825);
FORCEPROP 2 LAST PATH I38
J 0
(725 3975);
DISPLAY 0.680851 (725 3975);
DISPLAY INVISIBLE (725 3975);
FORCEADD OFFPAGE..1
(1000 4025);
FORCEPROP 2 LAST $XR0 138 
J 0
(718 4025);
DISPLAY 0.638298 (718 4025);
PAINT MONO (718 4025);
FORCEPROP 2 LAST CDS_LIB standard
J 0
(1000 4025);
PAINT MONO (1000 4025);
DISPLAY INVISIBLE (1000 4025);
FORCEPROP 1 LAST OFFPAGE TRUE
J 0
(1325 3900);
DISPLAY 0.872340 (1325 3900);
PAINT GREEN (1325 3900);
DISPLAY INVISIBLE (1325 3900);
FORCEPROP 1 LAST COMMENT_BODY TRUE
J 0
(1125 3925);
DISPLAY 0.872340 (1125 3925);
PAINT GREEN (1125 3925);
DISPLAY INVISIBLE (1125 3925);
FORCEPROP 2 LAST PATH I39
J 0
(725 4075);
DISPLAY 0.680851 (725 4075);
DISPLAY INVISIBLE (725 4075);
FORCEADD UNIVERSAL_GND..1
(750 -450);
FORCEPROP 3 LASTPIN (750 -400) SIG_NAME GND\g
J 0
(760 -390);
DISPLAY 0.659574 (760 -390);
PAINT MONO (760 -390);
DISPLAY INVISIBLE (760 -390);
FORCEPROP 2 LAST ROOM IO_SLOT
J 1
(525 -375);
DISPLAY 0.744681 (525 -375);
FORCEPROP 2 LAST CDS_LIB pure_quanta_power
J 0
(750 -450);
PAINT MONO (750 -450);
DISPLAY INVISIBLE (750 -450);
FORCEPROP 1 LAST HDL_POWER GND
J 1
(775 -525);
DISPLAY 0.872340 (775 -525);
PAINT GREEN (775 -525);
DISPLAY INVISIBLE (775 -525);
FORCEPROP 1 LAST PATH I4
J 0
(825 -450);
DISPLAY 0.872340 (825 -450);
PAINT AQUA (825 -450);
DISPLAY INVISIBLE (825 -450);
FORCEADD OFFPAGE..1
(2050 3500);
FORCEPROP 2 LAST $XR0 67 
J 0
(1799 3500);
DISPLAY 0.638298 (1799 3500);
PAINT MONO (1799 3500);
FORCEPROP 2 LAST CDS_LIB standard
J 0
(2050 3500);
DISPLAY INVISIBLE (2050 3500);
FORCEPROP 1 LAST OFFPAGE TRUE
J 0
(2375 3375);
DISPLAY 0.872340 (2375 3375);
PAINT GREEN (2375 3375);
DISPLAY INVISIBLE (2375 3375);
FORCEPROP 1 LAST COMMENT_BODY TRUE
J 0
(2175 3400);
DISPLAY 0.872340 (2175 3400);
PAINT GREEN (2175 3400);
DISPLAY INVISIBLE (2175 3400);
FORCEPROP 2 LAST PATH I40
J 0
(1800 3550);
DISPLAY 0.680851 (1800 3550);
DISPLAY INVISIBLE (1800 3550);
FORCEADD OFFPAGE..1
(2050 3550);
FORCEPROP 2 LAST $XR0 67 
J 0
(1799 3550);
DISPLAY 0.638298 (1799 3550);
PAINT MONO (1799 3550);
FORCEPROP 2 LAST CDS_LIB standard
J 0
(2050 3550);
DISPLAY INVISIBLE (2050 3550);
FORCEPROP 1 LAST OFFPAGE TRUE
J 0
(2375 3425);
DISPLAY 0.872340 (2375 3425);
PAINT GREEN (2375 3425);
DISPLAY INVISIBLE (2375 3425);
FORCEPROP 1 LAST COMMENT_BODY TRUE
J 0
(2175 3450);
DISPLAY 0.872340 (2175 3450);
PAINT GREEN (2175 3450);
DISPLAY INVISIBLE (2175 3450);
FORCEPROP 2 LAST PATH I41
J 0
(1800 3600);
DISPLAY 0.680851 (1800 3600);
DISPLAY INVISIBLE (1800 3600);
FORCEADD Q_RES..1
(1950 3775);
FORCEPROP 1 LAST LOCATION R3172
J 0
(1700 3775);
DISPLAY 0.787234 (1700 3775);
FORCEPROP 2 LAST $SEC 1
J 0
(1900 3975);
DISPLAY 0.680851 (1900 3975);
PAINT MONO (1900 3975);
DISPLAY INVISIBLE (1900 3975);
FORCEPROP 2 LAST CDS_SEC 1
J 0
(1900 3975);
DISPLAY 1.021277 (1900 3975);
DISPLAY INVISIBLE (1900 3975);
FORCEPROP 1 LASTPIN (1850 3775) $PN 1
J 0
(1862 3787);
DISPLAY 0.787234 (1862 3787);
FORCEPROP 1 LASTPIN (2050 3775) $PN 2
J 0
(2012 3787);
DISPLAY 0.787234 (2012 3787);
FORCEPROP 1 LAST PACK_TYPE 0402LF
J 0
(2225 3775);
DISPLAY 0.638298 (2225 3775);
FORCEPROP 1 LAST TOLERANCE 5%
J 0
(2150 3775);
DISPLAY 0.638298 (2150 3775);
FORCEPROP 1 LAST VALUE 0
J 2
(2125 3775);
DISPLAY 0.638298 (2125 3775);
FORCEPROP 1 LAST WATTAGE 1/16W
J 2
(2125 3900);
DISPLAY 0.638298 (2125 3900);
DISPLAY INVISIBLE (2125 3900);
FORCEPROP 1 LAST MATERIAL CHIP
J 0
(1825 3900);
DISPLAY 0.638298 (1825 3900);
DISPLAY INVISIBLE (1825 3900);
FORCEPROP 2 LAST CDS_LIB pure_quanta
J 0
(1950 3775);
PAINT MONO (1950 3775);
DISPLAY INVISIBLE (1950 3775);
FORCEPROP 1 LAST PATH I42
J 0
(1900 3925);
DISPLAY 0.978723 (1900 3925);
PAINT WHITE (1900 3925);
DISPLAY INVISIBLE (1900 3925);
FORCEPROP 1 LAST PART_NUMBER CS00002JB13
J 0
(1825 3850);
DISPLAY 0.638298 (1825 3850);
DISPLAY INVISIBLE (1825 3850);
FORCEADD Q_RES..1
(1950 4025);
FORCEPROP 1 LAST LOCATION R3169
J 0
(1725 4025);
DISPLAY 0.787234 (1725 4025);
FORCEPROP 2 LAST $SEC 1
J 0
(1900 4225);
DISPLAY 0.680851 (1900 4225);
PAINT MONO (1900 4225);
DISPLAY INVISIBLE (1900 4225);
FORCEPROP 2 LAST CDS_SEC 1
J 0
(1900 4225);
DISPLAY 1.021277 (1900 4225);
DISPLAY INVISIBLE (1900 4225);
FORCEPROP 1 LASTPIN (1850 4025) $PN 1
J 0
(1862 4037);
DISPLAY 0.787234 (1862 4037);
FORCEPROP 1 LASTPIN (2050 4025) $PN 2
J 0
(2012 4037);
DISPLAY 0.787234 (2012 4037);
FORCEPROP 1 LAST TOLERANCE 5%
J 0
(2150 4025);
DISPLAY 0.638298 (2150 4025);
FORCEPROP 1 LAST PACK_TYPE 0402LF
J 0
(2225 4025);
DISPLAY 0.638298 (2225 4025);
FORCEPROP 1 LAST MATERIAL CHIP
J 0
(1825 4150);
DISPLAY 0.638298 (1825 4150);
FORCEPROP 1 LAST VALUE 0
J 2
(2125 4025);
DISPLAY 0.638298 (2125 4025);
FORCEPROP 1 LAST WATTAGE 1/16W
J 2
(2125 4150);
DISPLAY 0.638298 (2125 4150);
FORCEPROP 2 LAST CDS_LIB pure_quanta
J 0
(1950 4025);
PAINT MONO (1950 4025);
DISPLAY INVISIBLE (1950 4025);
FORCEPROP 1 LAST PATH I43
J 0
(1900 4175);
DISPLAY 0.978723 (1900 4175);
PAINT WHITE (1900 4175);
DISPLAY INVISIBLE (1900 4175);
FORCEPROP 1 LAST PART_NUMBER CS00002JB13
J 0
(1825 4100);
DISPLAY 0.638298 (1825 4100);
DISPLAY INVISIBLE (1825 4100);
FORCEADD Q_RES..1
(1950 3975);
FORCEPROP 1 LAST LOCATION R3170
J 0
(1725 3975);
DISPLAY 0.787234 (1725 3975);
FORCEPROP 2 LAST $SEC 1
J 0
(1900 4175);
DISPLAY 0.680851 (1900 4175);
PAINT MONO (1900 4175);
DISPLAY INVISIBLE (1900 4175);
FORCEPROP 2 LAST CDS_SEC 1
J 0
(1900 4175);
DISPLAY 1.021277 (1900 4175);
DISPLAY INVISIBLE (1900 4175);
FORCEPROP 1 LASTPIN (1850 3975) $PN 1
J 0
(1862 3987);
DISPLAY 0.787234 (1862 3987);
FORCEPROP 1 LASTPIN (2050 3975) $PN 2
J 0
(2012 3987);
DISPLAY 0.787234 (2012 3987);
FORCEPROP 1 LAST VALUE 0
J 2
(2125 3975);
DISPLAY 0.638298 (2125 3975);
FORCEPROP 1 LAST TOLERANCE 5%
J 0
(2150 3975);
DISPLAY 0.638298 (2150 3975);
FORCEPROP 1 LAST PACK_TYPE 0402LF
J 0
(2225 3975);
DISPLAY 0.638298 (2225 3975);
FORCEPROP 1 LAST WATTAGE 1/16W
J 2
(2125 4100);
DISPLAY 0.638298 (2125 4100);
DISPLAY INVISIBLE (2125 4100);
FORCEPROP 1 LAST MATERIAL CHIP
J 0
(1825 4100);
DISPLAY 0.638298 (1825 4100);
DISPLAY INVISIBLE (1825 4100);
FORCEPROP 2 LAST CDS_LIB pure_quanta
J 0
(1950 3975);
PAINT MONO (1950 3975);
DISPLAY INVISIBLE (1950 3975);
FORCEPROP 1 LAST PATH I44
J 0
(1900 4125);
DISPLAY 0.978723 (1900 4125);
PAINT WHITE (1900 4125);
DISPLAY INVISIBLE (1900 4125);
FORCEPROP 1 LAST PART_NUMBER CS00002JB13
J 0
(1825 4050);
DISPLAY 0.638298 (1825 4050);
DISPLAY INVISIBLE (1825 4050);
FORCEADD Q_RES..1
(1950 3925);
FORCEPROP 1 LAST LOCATION R3171
J 0
(1725 3925);
DISPLAY 0.787234 (1725 3925);
FORCEPROP 2 LAST $SEC 1
J 0
(1900 4125);
DISPLAY 0.680851 (1900 4125);
PAINT MONO (1900 4125);
DISPLAY INVISIBLE (1900 4125);
FORCEPROP 2 LAST CDS_SEC 1
J 0
(1900 4125);
DISPLAY 1.021277 (1900 4125);
DISPLAY INVISIBLE (1900 4125);
FORCEPROP 1 LASTPIN (1850 3925) $PN 1
J 0
(1862 3937);
DISPLAY 0.787234 (1862 3937);
FORCEPROP 1 LASTPIN (2050 3925) $PN 2
J 0
(2012 3937);
DISPLAY 0.787234 (2012 3937);
FORCEPROP 1 LAST VALUE 0
J 2
(2125 3925);
DISPLAY 0.638298 (2125 3925);
FORCEPROP 1 LAST TOLERANCE 5%
J 0
(2150 3925);
DISPLAY 0.638298 (2150 3925);
FORCEPROP 1 LAST PACK_TYPE 0402LF
J 0
(2225 3925);
DISPLAY 0.638298 (2225 3925);
FORCEPROP 2 LAST CDS_LIB pure_quanta
J 0
(1950 3925);
PAINT MONO (1950 3925);
DISPLAY INVISIBLE (1950 3925);
FORCEPROP 1 LAST MATERIAL CHIP
J 0
(1825 4050);
DISPLAY 0.638298 (1825 4050);
DISPLAY INVISIBLE (1825 4050);
FORCEPROP 1 LAST WATTAGE 1/16W
J 2
(2125 4050);
DISPLAY 0.638298 (2125 4050);
DISPLAY INVISIBLE (2125 4050);
FORCEPROP 1 LAST PATH I45
J 0
(1900 4075);
DISPLAY 0.978723 (1900 4075);
PAINT WHITE (1900 4075);
DISPLAY INVISIBLE (1900 4075);
FORCEPROP 1 LAST PART_NUMBER CS00002JB13
J 0
(1825 4000);
DISPLAY 0.638298 (1825 4000);
DISPLAY INVISIBLE (1825 4000);
FORCEADD OFFPAGE..5
(2200 675);
FORCEPROP 2 LAST $XR1 143 
J 0
(1795 675);
DISPLAY 0.638298 (1795 675);
PAINT MONO (1795 675);
FORCEPROP 2 LAST $XR0 140 
J 0
(1915 675);
DISPLAY 0.638298 (1915 675);
PAINT MONO (1915 675);
FORCEPROP 2 LAST CDS_LIB standard
J 0
(2200 675);
PAINT MONO (2200 675);
DISPLAY INVISIBLE (2200 675);
FORCEPROP 1 LAST OFFPAGE TRUE
J 0
(2525 550);
DISPLAY 0.872340 (2525 550);
PAINT GREEN (2525 550);
DISPLAY INVISIBLE (2525 550);
FORCEPROP 1 LAST COMMENT_BODY TRUE
J 0
(2300 600);
DISPLAY 0.872340 (2300 600);
PAINT GREEN (2300 600);
DISPLAY INVISIBLE (2300 600);
FORCEPROP 2 LAST PATH I46
J 0
(1925 725);
DISPLAY 0.680851 (1925 725);
DISPLAY INVISIBLE (1925 725);
FORCEADD TAP..1
R 2
(3100 875);
FORCEPROP 3 LASTPIN (3150 875) SIG_NAME P5E_CPU1_G1_TX_C_DN<15>
J 0
(3160 885);
DISPLAY 0.659574 (3160 885);
PAINT MONO (3160 885);
DISPLAY INVISIBLE (3160 885);
FORCEPROP 1 LASTPIN (3150 875) BN 15
J 2
(3162 883);
DISPLAY 0.680851 (3162 883);
PAINT GREEN (3162 883);
FORCEPROP 2 LAST CDS_LIB standard
J 0
(3100 875);
PAINT MONO (3100 875);
DISPLAY INVISIBLE (3100 875);
FORCEPROP 1 LAST BODY_TYPE PLUMBING
J 2
(3100 925);
DISPLAY 0.872340 (3100 925);
PAINT GREEN (3100 925);
DISPLAY INVISIBLE (3100 925);
FORCEPROP 1 LAST HDL_TAP TRUE
J 2
(2775 750);
DISPLAY 0.872340 (2775 750);
PAINT GREEN (2775 750);
DISPLAY INVISIBLE (2775 750);
FORCEPROP 1 LAST PATH I47
J 2
(3102 875);
DISPLAY 0.872340 (3102 875);
PAINT GREEN (3102 875);
DISPLAY INVISIBLE (3102 875);
FORCEADD TAP..1
R 2
(3250 925);
FORCEPROP 3 LASTPIN (3300 925) SIG_NAME P5E_CPU1_G1_TX_C_DP<15>
J 0
(3310 935);
DISPLAY 0.659574 (3310 935);
PAINT MONO (3310 935);
DISPLAY INVISIBLE (3310 935);
FORCEPROP 1 LASTPIN (3300 925) BN 15
J 2
(3312 933);
DISPLAY 0.680851 (3312 933);
PAINT GREEN (3312 933);
FORCEPROP 2 LAST CDS_LIB standard
J 0
(3250 925);
PAINT MONO (3250 925);
DISPLAY INVISIBLE (3250 925);
FORCEPROP 1 LAST BODY_TYPE PLUMBING
J 2
(3250 975);
DISPLAY 0.872340 (3250 975);
PAINT GREEN (3250 975);
DISPLAY INVISIBLE (3250 975);
FORCEPROP 1 LAST HDL_TAP TRUE
J 2
(2925 800);
DISPLAY 0.872340 (2925 800);
PAINT GREEN (2925 800);
DISPLAY INVISIBLE (2925 800);
FORCEPROP 1 LAST PATH I48
J 2
(3252 925);
DISPLAY 0.872340 (3252 925);
PAINT GREEN (3252 925);
DISPLAY INVISIBLE (3252 925);
FORCEADD UNIVERSAL_GND..1
(3650 175);
FORCEPROP 3 LASTPIN (3650 225) SIG_NAME GND\g
J 0
(3660 235);
DISPLAY 0.659574 (3660 235);
PAINT MONO (3660 235);
DISPLAY INVISIBLE (3660 235);
FORCEPROP 2 LAST CDS_LIB pure_quanta_power
J 0
(3650 175);
DISPLAY INVISIBLE (3650 175);
FORCEPROP 1 LAST HDL_POWER GND
J 1
(3675 100);
DISPLAY 0.872340 (3675 100);
PAINT GREEN (3675 100);
DISPLAY INVISIBLE (3675 100);
FORCEPROP 1 LAST PATH I49
J 0
(3725 175);
DISPLAY 0.872340 (3725 175);
PAINT AQUA (3725 175);
DISPLAY INVISIBLE (3725 175);
FORCEADD OFFPAGE..5
(2400 -625);
FORCEPROP 2 LAST $XR1 137 
J 0
(2056 -625);
DISPLAY 0.638298 (2056 -625);
PAINT MONO (2056 -625);
FORCEPROP 2 LAST $XR0 80 
J 0
(2176 -625);
DISPLAY 0.638298 (2176 -625);
PAINT MONO (2176 -625);
FORCEPROP 2 LAST CDS_LIB standard
J 0
(2400 -625);
PAINT MONO (2400 -625);
DISPLAY INVISIBLE (2400 -625);
FORCEPROP 1 LAST OFFPAGE TRUE
J 0
(2725 -750);
DISPLAY 0.872340 (2725 -750);
PAINT GREEN (2725 -750);
DISPLAY INVISIBLE (2725 -750);
FORCEPROP 1 LAST COMMENT_BODY TRUE
J 0
(2500 -700);
DISPLAY 0.872340 (2500 -700);
PAINT GREEN (2500 -700);
DISPLAY INVISIBLE (2500 -700);
FORCEPROP 2 LAST PATH I5
J 0
(2125 -575);
DISPLAY 0.680851 (2125 -575);
DISPLAY INVISIBLE (2125 -575);
FORCEADD TAP..1
R 2
(3100 1025);
FORCEPROP 3 LASTPIN (3150 1025) SIG_NAME P5E_CPU1_G1_TX_C_DN<14>
J 0
(3160 1035);
DISPLAY 0.659574 (3160 1035);
PAINT MONO (3160 1035);
DISPLAY INVISIBLE (3160 1035);
FORCEPROP 1 LASTPIN (3150 1025) BN 14
J 2
(3162 1033);
DISPLAY 0.680851 (3162 1033);
PAINT GREEN (3162 1033);
FORCEPROP 2 LAST CDS_LIB standard
J 0
(3100 1025);
PAINT MONO (3100 1025);
DISPLAY INVISIBLE (3100 1025);
FORCEPROP 1 LAST BODY_TYPE PLUMBING
J 2
(3100 1075);
DISPLAY 0.872340 (3100 1075);
PAINT GREEN (3100 1075);
DISPLAY INVISIBLE (3100 1075);
FORCEPROP 1 LAST HDL_TAP TRUE
J 2
(2775 900);
DISPLAY 0.872340 (2775 900);
PAINT GREEN (2775 900);
DISPLAY INVISIBLE (2775 900);
FORCEPROP 1 LAST PATH I50
J 2
(3102 1025);
DISPLAY 0.872340 (3102 1025);
PAINT GREEN (3102 1025);
DISPLAY INVISIBLE (3102 1025);
FORCEADD TAP..1
R 2
(3250 1075);
FORCEPROP 3 LASTPIN (3300 1075) SIG_NAME P5E_CPU1_G1_TX_C_DP<14>
J 0
(3310 1085);
DISPLAY 0.659574 (3310 1085);
PAINT MONO (3310 1085);
DISPLAY INVISIBLE (3310 1085);
FORCEPROP 1 LASTPIN (3300 1075) BN 14
J 2
(3312 1083);
DISPLAY 0.680851 (3312 1083);
PAINT GREEN (3312 1083);
FORCEPROP 2 LAST CDS_LIB standard
J 0
(3250 1075);
PAINT MONO (3250 1075);
DISPLAY INVISIBLE (3250 1075);
FORCEPROP 1 LAST BODY_TYPE PLUMBING
J 2
(3250 1125);
DISPLAY 0.872340 (3250 1125);
PAINT GREEN (3250 1125);
DISPLAY INVISIBLE (3250 1125);
FORCEPROP 1 LAST HDL_TAP TRUE
J 2
(2925 950);
DISPLAY 0.872340 (2925 950);
PAINT GREEN (2925 950);
DISPLAY INVISIBLE (2925 950);
FORCEPROP 1 LAST PATH I51
J 2
(3252 1075);
DISPLAY 0.872340 (3252 1075);
PAINT GREEN (3252 1075);
DISPLAY INVISIBLE (3252 1075);
FORCEADD TAP..1
R 2
(3100 1325);
FORCEPROP 3 LASTPIN (3150 1325) SIG_NAME P5E_CPU1_G1_TX_C_DN<12>
J 0
(3160 1335);
DISPLAY 0.659574 (3160 1335);
PAINT MONO (3160 1335);
DISPLAY INVISIBLE (3160 1335);
FORCEPROP 1 LASTPIN (3150 1325) BN 12
J 2
(3162 1333);
DISPLAY 0.680851 (3162 1333);
PAINT GREEN (3162 1333);
FORCEPROP 2 LAST CDS_LIB standard
J 0
(3100 1325);
PAINT MONO (3100 1325);
DISPLAY INVISIBLE (3100 1325);
FORCEPROP 1 LAST BODY_TYPE PLUMBING
J 2
(3100 1375);
DISPLAY 0.872340 (3100 1375);
PAINT GREEN (3100 1375);
DISPLAY INVISIBLE (3100 1375);
FORCEPROP 1 LAST HDL_TAP TRUE
J 2
(2775 1200);
DISPLAY 0.872340 (2775 1200);
PAINT GREEN (2775 1200);
DISPLAY INVISIBLE (2775 1200);
FORCEPROP 1 LAST PATH I52
J 2
(3102 1325);
DISPLAY 0.872340 (3102 1325);
PAINT GREEN (3102 1325);
DISPLAY INVISIBLE (3102 1325);
FORCEADD TAP..1
R 2
(3100 1475);
FORCEPROP 3 LASTPIN (3150 1475) SIG_NAME P5E_CPU1_G1_TX_C_DN<11>
J 0
(3160 1485);
DISPLAY 0.659574 (3160 1485);
PAINT MONO (3160 1485);
DISPLAY INVISIBLE (3160 1485);
FORCEPROP 1 LASTPIN (3150 1475) BN 11
J 2
(3162 1483);
DISPLAY 0.680851 (3162 1483);
PAINT GREEN (3162 1483);
FORCEPROP 2 LAST CDS_LIB standard
J 0
(3100 1475);
PAINT MONO (3100 1475);
DISPLAY INVISIBLE (3100 1475);
FORCEPROP 1 LAST BODY_TYPE PLUMBING
J 2
(3100 1525);
DISPLAY 0.872340 (3100 1525);
PAINT GREEN (3100 1525);
DISPLAY INVISIBLE (3100 1525);
FORCEPROP 1 LAST HDL_TAP TRUE
J 2
(2775 1350);
DISPLAY 0.872340 (2775 1350);
PAINT GREEN (2775 1350);
DISPLAY INVISIBLE (2775 1350);
FORCEPROP 1 LAST PATH I53
J 2
(3102 1475);
DISPLAY 0.872340 (3102 1475);
PAINT GREEN (3102 1475);
DISPLAY INVISIBLE (3102 1475);
FORCEADD TAP..1
R 2
(3250 1375);
FORCEPROP 3 LASTPIN (3300 1375) SIG_NAME P5E_CPU1_G1_TX_C_DP<12>
J 0
(3310 1385);
DISPLAY 0.659574 (3310 1385);
PAINT MONO (3310 1385);
DISPLAY INVISIBLE (3310 1385);
FORCEPROP 1 LASTPIN (3300 1375) BN 12
J 2
(3312 1383);
DISPLAY 0.680851 (3312 1383);
PAINT GREEN (3312 1383);
FORCEPROP 2 LAST CDS_LIB standard
J 0
(3250 1375);
PAINT MONO (3250 1375);
DISPLAY INVISIBLE (3250 1375);
FORCEPROP 1 LAST BODY_TYPE PLUMBING
J 2
(3250 1425);
DISPLAY 0.872340 (3250 1425);
PAINT GREEN (3250 1425);
DISPLAY INVISIBLE (3250 1425);
FORCEPROP 1 LAST HDL_TAP TRUE
J 2
(2925 1250);
DISPLAY 0.872340 (2925 1250);
PAINT GREEN (2925 1250);
DISPLAY INVISIBLE (2925 1250);
FORCEPROP 1 LAST PATH I54
J 2
(3252 1375);
DISPLAY 0.872340 (3252 1375);
PAINT GREEN (3252 1375);
DISPLAY INVISIBLE (3252 1375);
FORCEADD TAP..1
R 2
(3100 1625);
FORCEPROP 3 LASTPIN (3150 1625) SIG_NAME P5E_CPU1_G1_TX_C_DN<10>
J 0
(3160 1635);
DISPLAY 0.659574 (3160 1635);
PAINT MONO (3160 1635);
DISPLAY INVISIBLE (3160 1635);
FORCEPROP 1 LASTPIN (3150 1625) BN 10
J 2
(3162 1633);
DISPLAY 0.680851 (3162 1633);
PAINT GREEN (3162 1633);
FORCEPROP 2 LAST CDS_LIB standard
J 0
(3100 1625);
PAINT MONO (3100 1625);
DISPLAY INVISIBLE (3100 1625);
FORCEPROP 1 LAST BODY_TYPE PLUMBING
J 2
(3100 1675);
DISPLAY 0.872340 (3100 1675);
PAINT GREEN (3100 1675);
DISPLAY INVISIBLE (3100 1675);
FORCEPROP 1 LAST HDL_TAP TRUE
J 2
(2775 1500);
DISPLAY 0.872340 (2775 1500);
PAINT GREEN (2775 1500);
DISPLAY INVISIBLE (2775 1500);
FORCEPROP 1 LAST PATH I55
J 2
(3102 1625);
DISPLAY 0.872340 (3102 1625);
PAINT GREEN (3102 1625);
DISPLAY INVISIBLE (3102 1625);
FORCEADD TAP..1
R 2
(3250 1525);
FORCEPROP 3 LASTPIN (3300 1525) SIG_NAME P5E_CPU1_G1_TX_C_DP<11>
J 0
(3310 1535);
DISPLAY 0.659574 (3310 1535);
PAINT MONO (3310 1535);
DISPLAY INVISIBLE (3310 1535);
FORCEPROP 1 LASTPIN (3300 1525) BN 11
J 2
(3312 1533);
DISPLAY 0.680851 (3312 1533);
PAINT GREEN (3312 1533);
FORCEPROP 2 LAST CDS_LIB standard
J 0
(3250 1525);
PAINT MONO (3250 1525);
DISPLAY INVISIBLE (3250 1525);
FORCEPROP 1 LAST BODY_TYPE PLUMBING
J 2
(3250 1575);
DISPLAY 0.872340 (3250 1575);
PAINT GREEN (3250 1575);
DISPLAY INVISIBLE (3250 1575);
FORCEPROP 1 LAST HDL_TAP TRUE
J 2
(2925 1400);
DISPLAY 0.872340 (2925 1400);
PAINT GREEN (2925 1400);
DISPLAY INVISIBLE (2925 1400);
FORCEPROP 1 LAST PATH I56
J 2
(3252 1525);
DISPLAY 0.872340 (3252 1525);
PAINT GREEN (3252 1525);
DISPLAY INVISIBLE (3252 1525);
FORCEADD TAP..1
R 2
(3250 1675);
FORCEPROP 3 LASTPIN (3300 1675) SIG_NAME P5E_CPU1_G1_TX_C_DP<10>
J 0
(3310 1685);
DISPLAY 0.659574 (3310 1685);
PAINT MONO (3310 1685);
DISPLAY INVISIBLE (3310 1685);
FORCEPROP 1 LASTPIN (3300 1675) BN 10
J 2
(3312 1683);
DISPLAY 0.680851 (3312 1683);
PAINT GREEN (3312 1683);
FORCEPROP 2 LAST CDS_LIB standard
J 0
(3250 1675);
PAINT MONO (3250 1675);
DISPLAY INVISIBLE (3250 1675);
FORCEPROP 1 LAST BODY_TYPE PLUMBING
J 2
(3250 1725);
DISPLAY 0.872340 (3250 1725);
PAINT GREEN (3250 1725);
DISPLAY INVISIBLE (3250 1725);
FORCEPROP 1 LAST HDL_TAP TRUE
J 2
(2925 1550);
DISPLAY 0.872340 (2925 1550);
PAINT GREEN (2925 1550);
DISPLAY INVISIBLE (2925 1550);
FORCEPROP 1 LAST PATH I57
J 2
(3252 1675);
DISPLAY 0.872340 (3252 1675);
PAINT GREEN (3252 1675);
DISPLAY INVISIBLE (3252 1675);
FORCEADD TAP..1
R 2
(3100 1775);
FORCEPROP 3 LASTPIN (3150 1775) SIG_NAME P5E_CPU1_G1_TX_C_DN<9>
J 0
(3160 1785);
DISPLAY 0.659574 (3160 1785);
PAINT MONO (3160 1785);
DISPLAY INVISIBLE (3160 1785);
FORCEPROP 1 LASTPIN (3150 1775) BN 9
J 2
(3162 1783);
DISPLAY 0.680851 (3162 1783);
PAINT GREEN (3162 1783);
FORCEPROP 2 LAST CDS_LIB standard
J 0
(3100 1775);
PAINT MONO (3100 1775);
DISPLAY INVISIBLE (3100 1775);
FORCEPROP 1 LAST BODY_TYPE PLUMBING
J 2
(3100 1825);
DISPLAY 0.872340 (3100 1825);
PAINT GREEN (3100 1825);
DISPLAY INVISIBLE (3100 1825);
FORCEPROP 1 LAST HDL_TAP TRUE
J 2
(2775 1650);
DISPLAY 0.872340 (2775 1650);
PAINT GREEN (2775 1650);
DISPLAY INVISIBLE (2775 1650);
FORCEPROP 1 LAST PATH I58
J 2
(3102 1775);
DISPLAY 0.872340 (3102 1775);
PAINT GREEN (3102 1775);
DISPLAY INVISIBLE (3102 1775);
FORCEADD TAP..1
R 2
(3100 1925);
FORCEPROP 3 LASTPIN (3150 1925) SIG_NAME P5E_CPU1_G1_TX_C_DN<8>
J 0
(3160 1935);
DISPLAY 0.659574 (3160 1935);
PAINT MONO (3160 1935);
DISPLAY INVISIBLE (3160 1935);
FORCEPROP 1 LASTPIN (3150 1925) BN 8
J 2
(3162 1933);
DISPLAY 0.680851 (3162 1933);
PAINT GREEN (3162 1933);
FORCEPROP 2 LAST CDS_LIB standard
J 0
(3100 1925);
PAINT MONO (3100 1925);
DISPLAY INVISIBLE (3100 1925);
FORCEPROP 1 LAST BODY_TYPE PLUMBING
J 2
(3100 1975);
DISPLAY 0.872340 (3100 1975);
PAINT GREEN (3100 1975);
DISPLAY INVISIBLE (3100 1975);
FORCEPROP 1 LAST HDL_TAP TRUE
J 2
(2775 1800);
DISPLAY 0.872340 (2775 1800);
PAINT GREEN (2775 1800);
DISPLAY INVISIBLE (2775 1800);
FORCEPROP 1 LAST PATH I59
J 2
(3102 1925);
DISPLAY 0.872340 (3102 1925);
PAINT GREEN (3102 1925);
DISPLAY INVISIBLE (3102 1925);
FORCEADD OFFPAGE..5
(2400 -450);
FORCEPROP 2 LAST $XR1 80 
J 0
(2055 -450);
DISPLAY 0.638298 (2055 -450);
PAINT MONO (2055 -450);
FORCEPROP 2 LAST $XR0 137 
J 0
(2145 -450);
DISPLAY 0.638298 (2145 -450);
PAINT MONO (2145 -450);
FORCEPROP 2 LAST CDS_LIB standard
J 0
(2400 -450);
PAINT MONO (2400 -450);
DISPLAY INVISIBLE (2400 -450);
FORCEPROP 1 LAST OFFPAGE TRUE
J 0
(2725 -575);
DISPLAY 0.872340 (2725 -575);
PAINT GREEN (2725 -575);
DISPLAY INVISIBLE (2725 -575);
FORCEPROP 1 LAST COMMENT_BODY TRUE
J 0
(2500 -525);
DISPLAY 0.872340 (2500 -525);
PAINT GREEN (2500 -525);
DISPLAY INVISIBLE (2500 -525);
FORCEPROP 2 LAST PATH I6
J 0
(2125 -400);
DISPLAY 0.680851 (2125 -400);
DISPLAY INVISIBLE (2125 -400);
FORCEADD TAP..1
R 2
(3250 1975);
FORCEPROP 3 LASTPIN (3300 1975) SIG_NAME P5E_CPU1_G1_TX_C_DP<8>
J 0
(3310 1985);
DISPLAY 0.659574 (3310 1985);
PAINT MONO (3310 1985);
DISPLAY INVISIBLE (3310 1985);
FORCEPROP 1 LASTPIN (3300 1975) BN 8
J 2
(3312 1983);
DISPLAY 0.680851 (3312 1983);
PAINT GREEN (3312 1983);
FORCEPROP 2 LAST CDS_LIB standard
J 0
(3250 1975);
PAINT MONO (3250 1975);
DISPLAY INVISIBLE (3250 1975);
FORCEPROP 1 LAST BODY_TYPE PLUMBING
J 2
(3250 2025);
DISPLAY 0.872340 (3250 2025);
PAINT GREEN (3250 2025);
DISPLAY INVISIBLE (3250 2025);
FORCEPROP 1 LAST HDL_TAP TRUE
J 2
(2925 1850);
DISPLAY 0.872340 (2925 1850);
PAINT GREEN (2925 1850);
DISPLAY INVISIBLE (2925 1850);
FORCEPROP 1 LAST PATH I60
J 2
(3252 1975);
DISPLAY 0.872340 (3252 1975);
PAINT GREEN (3252 1975);
DISPLAY INVISIBLE (3252 1975);
FORCEADD TAP..1
R 2
(3250 1825);
FORCEPROP 3 LASTPIN (3300 1825) SIG_NAME P5E_CPU1_G1_TX_C_DP<9>
J 0
(3310 1835);
DISPLAY 0.659574 (3310 1835);
PAINT MONO (3310 1835);
DISPLAY INVISIBLE (3310 1835);
FORCEPROP 1 LASTPIN (3300 1825) BN 9
J 2
(3312 1833);
DISPLAY 0.680851 (3312 1833);
PAINT GREEN (3312 1833);
FORCEPROP 2 LAST CDS_LIB standard
J 0
(3250 1825);
PAINT MONO (3250 1825);
DISPLAY INVISIBLE (3250 1825);
FORCEPROP 1 LAST BODY_TYPE PLUMBING
J 2
(3250 1875);
DISPLAY 0.872340 (3250 1875);
PAINT GREEN (3250 1875);
DISPLAY INVISIBLE (3250 1875);
FORCEPROP 1 LAST HDL_TAP TRUE
J 2
(2925 1700);
DISPLAY 0.872340 (2925 1700);
PAINT GREEN (2925 1700);
DISPLAY INVISIBLE (2925 1700);
FORCEPROP 1 LAST PATH I61
J 2
(3252 1825);
DISPLAY 0.872340 (3252 1825);
PAINT GREEN (3252 1825);
DISPLAY INVISIBLE (3252 1825);
FORCEADD OFFPAGE..5
(2375 2175);
FORCEPROP 2 LAST $XR1 143 
J 0
(2000 2175);
DISPLAY 0.638298 (2000 2175);
PAINT MONO (2000 2175);
FORCEPROP 2 LAST $XR0 140 
J 0
(2120 2175);
DISPLAY 0.638298 (2120 2175);
PAINT MONO (2120 2175);
FORCEPROP 2 LAST CDS_LIB standard
J 0
(2375 2175);
PAINT MONO (2375 2175);
DISPLAY INVISIBLE (2375 2175);
FORCEPROP 1 LAST OFFPAGE TRUE
J 0
(2700 2050);
DISPLAY 0.872340 (2700 2050);
PAINT GREEN (2700 2050);
DISPLAY INVISIBLE (2700 2050);
FORCEPROP 1 LAST COMMENT_BODY TRUE
J 0
(2475 2100);
DISPLAY 0.872340 (2475 2100);
PAINT GREEN (2475 2100);
DISPLAY INVISIBLE (2475 2100);
FORCEPROP 2 LAST PATH I62
J 0
(2125 2225);
DISPLAY 0.680851 (2125 2225);
DISPLAY INVISIBLE (2125 2225);
FORCEADD OFFPAGE..2
(2125 2550);
FORCEPROP 2 LAST $XR2 138 
J 0
(2524 2550);
DISPLAY 0.638298 (2524 2550);
PAINT MONO (2524 2550);
FORCEPROP 2 LAST $XR1 80 
J 0
(2434 2550);
DISPLAY 0.638298 (2434 2550);
PAINT MONO (2434 2550);
FORCEPROP 2 LAST $XR0 137 
J 0
(2314 2550);
DISPLAY 0.638298 (2314 2550);
PAINT MONO (2314 2550);
FORCEPROP 2 LAST CDS_LIB standard
J 0
(2125 2550);
DISPLAY INVISIBLE (2125 2550);
FORCEPROP 1 LAST OFFPAGE TRUE
J 0
(2450 2425);
DISPLAY 0.872340 (2450 2425);
PAINT GREEN (2450 2425);
DISPLAY INVISIBLE (2450 2425);
FORCEPROP 1 LAST COMMENT_BODY TRUE
J 0
(2080 2455);
DISPLAY 0.872340 (2080 2455);
PAINT GREEN (2080 2455);
DISPLAY INVISIBLE (2080 2455);
FORCEPROP 2 LAST PATH I63
J 0
(2575 2600);
DISPLAY 0.680851 (2575 2600);
DISPLAY INVISIBLE (2575 2600);
FORCEADD OFFPAGE..2
(2075 2750);
FORCEPROP 2 LAST $XR1 137 
J 0
(2354 2750);
DISPLAY 0.638298 (2354 2750);
PAINT MONO (2354 2750);
FORCEPROP 2 LAST $XR0 80 
J 0
(2264 2750);
DISPLAY 0.638298 (2264 2750);
PAINT MONO (2264 2750);
FORCEPROP 2 LAST CDS_LIB standard
J 0
(2075 2750);
DISPLAY INVISIBLE (2075 2750);
FORCEPROP 1 LAST OFFPAGE TRUE
J 0
(2400 2625);
DISPLAY 0.872340 (2400 2625);
PAINT GREEN (2400 2625);
DISPLAY INVISIBLE (2400 2625);
FORCEPROP 1 LAST COMMENT_BODY TRUE
J 0
(2030 2655);
DISPLAY 0.872340 (2030 2655);
PAINT GREEN (2030 2655);
DISPLAY INVISIBLE (2030 2655);
FORCEPROP 2 LAST PATH I64
J 0
(2400 2800);
DISPLAY 0.680851 (2400 2800);
DISPLAY INVISIBLE (2400 2800);
FORCEADD OFFPAGE..2
(2075 2850);
FORCEPROP 2 LAST $XR3 139 
J 0
(2624 2850);
DISPLAY 0.638298 (2624 2850);
PAINT MONO (2624 2850);
FORCEPROP 2 LAST $XR2 138 
J 0
(2504 2850);
DISPLAY 0.638298 (2504 2850);
PAINT MONO (2504 2850);
FORCEPROP 2 LAST $XR1 137 
J 0
(2384 2850);
DISPLAY 0.638298 (2384 2850);
PAINT MONO (2384 2850);
FORCEPROP 2 LAST $XR0 142 
J 0
(2264 2850);
DISPLAY 0.638298 (2264 2850);
PAINT MONO (2264 2850);
FORCEPROP 2 LAST CDS_LIB standard
J 0
(2075 2850);
DISPLAY INVISIBLE (2075 2850);
FORCEPROP 1 LAST OFFPAGE TRUE
J 0
(2400 2725);
DISPLAY 0.872340 (2400 2725);
PAINT GREEN (2400 2725);
DISPLAY INVISIBLE (2400 2725);
FORCEPROP 1 LAST COMMENT_BODY TRUE
J 0
(2030 2755);
DISPLAY 0.872340 (2030 2755);
PAINT GREEN (2030 2755);
DISPLAY INVISIBLE (2030 2755);
FORCEPROP 2 LAST PATH I65
J 0
(2750 2900);
DISPLAY 0.680851 (2750 2900);
DISPLAY INVISIBLE (2750 2900);
FORCEADD OFFPAGE..1
(2375 3625);
FORCEPROP 2 LAST $XR0 55 
J 0
(2124 3625);
DISPLAY 0.638298 (2124 3625);
PAINT MONO (2124 3625);
FORCEPROP 2 LAST CDS_LIB standard
J 0
(2375 3625);
PAINT MONO (2375 3625);
DISPLAY INVISIBLE (2375 3625);
FORCEPROP 1 LAST OFFPAGE TRUE
J 0
(2700 3500);
DISPLAY 0.872340 (2700 3500);
PAINT GREEN (2700 3500);
DISPLAY INVISIBLE (2700 3500);
FORCEPROP 1 LAST COMMENT_BODY TRUE
J 0
(2500 3525);
DISPLAY 0.872340 (2500 3525);
PAINT GREEN (2500 3525);
DISPLAY INVISIBLE (2500 3525);
FORCEPROP 2 LAST PATH I66
J 0
(2125 3675);
DISPLAY 0.680851 (2125 3675);
DISPLAY INVISIBLE (2125 3675);
FORCEADD OFFPAGE..1
(2375 3675);
FORCEPROP 2 LAST $XR0 55 
J 0
(2124 3675);
DISPLAY 0.638298 (2124 3675);
PAINT MONO (2124 3675);
FORCEPROP 2 LAST CDS_LIB standard
J 0
(2375 3675);
PAINT MONO (2375 3675);
DISPLAY INVISIBLE (2375 3675);
FORCEPROP 1 LAST OFFPAGE TRUE
J 0
(2700 3550);
DISPLAY 0.872340 (2700 3550);
PAINT GREEN (2700 3550);
DISPLAY INVISIBLE (2700 3550);
FORCEPROP 1 LAST COMMENT_BODY TRUE
J 0
(2500 3575);
DISPLAY 0.872340 (2500 3575);
PAINT GREEN (2500 3575);
DISPLAY INVISIBLE (2500 3575);
FORCEPROP 2 LAST PATH I67
J 0
(2125 3725);
DISPLAY 0.680851 (2125 3725);
DISPLAY INVISIBLE (2125 3725);
FORCEADD TAP..1
R 2
(3100 2275);
FORCEPROP 3 LASTPIN (3150 2275) SIG_NAME P5E_CPU1_G1_TX_C_DN<7>
J 0
(3160 2285);
DISPLAY 0.659574 (3160 2285);
PAINT MONO (3160 2285);
DISPLAY INVISIBLE (3160 2285);
FORCEPROP 1 LASTPIN (3150 2275) BN 7
J 2
(3162 2283);
DISPLAY 0.680851 (3162 2283);
PAINT GREEN (3162 2283);
FORCEPROP 2 LAST CDS_LIB standard
J 0
(3100 2275);
PAINT MONO (3100 2275);
DISPLAY INVISIBLE (3100 2275);
FORCEPROP 1 LAST BODY_TYPE PLUMBING
J 2
(3100 2325);
DISPLAY 0.872340 (3100 2325);
PAINT GREEN (3100 2325);
DISPLAY INVISIBLE (3100 2325);
FORCEPROP 1 LAST HDL_TAP TRUE
J 2
(2775 2150);
DISPLAY 0.872340 (2775 2150);
PAINT GREEN (2775 2150);
DISPLAY INVISIBLE (2775 2150);
FORCEPROP 1 LAST PATH I68
J 2
(3102 2275);
DISPLAY 0.872340 (3102 2275);
PAINT GREEN (3102 2275);
DISPLAY INVISIBLE (3102 2275);
FORCEADD TAP..1
R 2
(3100 2425);
FORCEPROP 3 LASTPIN (3150 2425) SIG_NAME P5E_CPU1_G1_TX_C_DN<6>
J 0
(3160 2435);
DISPLAY 0.659574 (3160 2435);
PAINT MONO (3160 2435);
DISPLAY INVISIBLE (3160 2435);
FORCEPROP 1 LASTPIN (3150 2425) BN 6
J 2
(3162 2433);
DISPLAY 0.680851 (3162 2433);
PAINT GREEN (3162 2433);
FORCEPROP 2 LAST CDS_LIB standard
J 0
(3100 2425);
PAINT MONO (3100 2425);
DISPLAY INVISIBLE (3100 2425);
FORCEPROP 1 LAST BODY_TYPE PLUMBING
J 2
(3100 2475);
DISPLAY 0.872340 (3100 2475);
PAINT GREEN (3100 2475);
DISPLAY INVISIBLE (3100 2475);
FORCEPROP 1 LAST HDL_TAP TRUE
J 2
(2775 2300);
DISPLAY 0.872340 (2775 2300);
PAINT GREEN (2775 2300);
DISPLAY INVISIBLE (2775 2300);
FORCEPROP 1 LAST PATH I69
J 2
(3102 2425);
DISPLAY 0.872340 (3102 2425);
PAINT GREEN (3102 2425);
DISPLAY INVISIBLE (3102 2425);
FORCEADD OFFPAGE..5
(2400 -275);
FORCEPROP 2 LAST $XR1 137 
J 0
(2056 -275);
DISPLAY 0.638298 (2056 -275);
PAINT MONO (2056 -275);
FORCEPROP 2 LAST $XR0 80 
J 0
(2176 -275);
DISPLAY 0.638298 (2176 -275);
PAINT MONO (2176 -275);
FORCEPROP 2 LAST CDS_LIB standard
J 0
(2400 -275);
PAINT MONO (2400 -275);
DISPLAY INVISIBLE (2400 -275);
FORCEPROP 1 LAST OFFPAGE TRUE
J 0
(2725 -400);
DISPLAY 0.872340 (2725 -400);
PAINT GREEN (2725 -400);
DISPLAY INVISIBLE (2725 -400);
FORCEPROP 1 LAST COMMENT_BODY TRUE
J 0
(2500 -350);
DISPLAY 0.872340 (2500 -350);
PAINT GREEN (2500 -350);
DISPLAY INVISIBLE (2500 -350);
FORCEPROP 2 LAST PATH I7
J 0
(2125 -225);
DISPLAY 0.680851 (2125 -225);
DISPLAY INVISIBLE (2125 -225);
FORCEADD TAP..1
R 2
(3250 2325);
FORCEPROP 3 LASTPIN (3300 2325) SIG_NAME P5E_CPU1_G1_TX_C_DP<7>
J 0
(3310 2335);
DISPLAY 0.659574 (3310 2335);
PAINT MONO (3310 2335);
DISPLAY INVISIBLE (3310 2335);
FORCEPROP 1 LASTPIN (3300 2325) BN 7
J 2
(3312 2333);
DISPLAY 0.680851 (3312 2333);
PAINT GREEN (3312 2333);
FORCEPROP 2 LAST CDS_LIB standard
J 0
(3250 2325);
PAINT MONO (3250 2325);
DISPLAY INVISIBLE (3250 2325);
FORCEPROP 1 LAST BODY_TYPE PLUMBING
J 2
(3250 2375);
DISPLAY 0.872340 (3250 2375);
PAINT GREEN (3250 2375);
DISPLAY INVISIBLE (3250 2375);
FORCEPROP 1 LAST HDL_TAP TRUE
J 2
(2925 2200);
DISPLAY 0.872340 (2925 2200);
PAINT GREEN (2925 2200);
DISPLAY INVISIBLE (2925 2200);
FORCEPROP 1 LAST PATH I70
J 2
(3252 2325);
DISPLAY 0.872340 (3252 2325);
PAINT GREEN (3252 2325);
DISPLAY INVISIBLE (3252 2325);
FORCEADD TAP..1
R 2
(3250 2475);
FORCEPROP 3 LASTPIN (3300 2475) SIG_NAME P5E_CPU1_G1_TX_C_DP<6>
J 0
(3310 2485);
DISPLAY 0.659574 (3310 2485);
PAINT MONO (3310 2485);
DISPLAY INVISIBLE (3310 2485);
FORCEPROP 1 LASTPIN (3300 2475) BN 6
J 2
(3312 2483);
DISPLAY 0.680851 (3312 2483);
PAINT GREEN (3312 2483);
FORCEPROP 2 LAST CDS_LIB standard
J 0
(3250 2475);
PAINT MONO (3250 2475);
DISPLAY INVISIBLE (3250 2475);
FORCEPROP 1 LAST BODY_TYPE PLUMBING
J 2
(3250 2525);
DISPLAY 0.872340 (3250 2525);
PAINT GREEN (3250 2525);
DISPLAY INVISIBLE (3250 2525);
FORCEPROP 1 LAST HDL_TAP TRUE
J 2
(2925 2350);
DISPLAY 0.872340 (2925 2350);
PAINT GREEN (2925 2350);
DISPLAY INVISIBLE (2925 2350);
FORCEPROP 1 LAST PATH I71
J 2
(3252 2475);
DISPLAY 0.872340 (3252 2475);
PAINT GREEN (3252 2475);
DISPLAY INVISIBLE (3252 2475);
FORCEADD TAP..1
R 2
(3100 2575);
FORCEPROP 3 LASTPIN (3150 2575) SIG_NAME P5E_CPU1_G1_TX_C_DN<5>
J 0
(3160 2585);
DISPLAY 0.659574 (3160 2585);
PAINT MONO (3160 2585);
DISPLAY INVISIBLE (3160 2585);
FORCEPROP 1 LASTPIN (3150 2575) BN 5
J 2
(3162 2583);
DISPLAY 0.680851 (3162 2583);
PAINT GREEN (3162 2583);
FORCEPROP 2 LAST CDS_LIB standard
J 0
(3100 2575);
PAINT MONO (3100 2575);
DISPLAY INVISIBLE (3100 2575);
FORCEPROP 1 LAST BODY_TYPE PLUMBING
J 2
(3100 2625);
DISPLAY 0.872340 (3100 2625);
PAINT GREEN (3100 2625);
DISPLAY INVISIBLE (3100 2625);
FORCEPROP 1 LAST HDL_TAP TRUE
J 2
(2775 2450);
DISPLAY 0.872340 (2775 2450);
PAINT GREEN (2775 2450);
DISPLAY INVISIBLE (2775 2450);
FORCEPROP 1 LAST PATH I72
J 2
(3102 2575);
DISPLAY 0.872340 (3102 2575);
PAINT GREEN (3102 2575);
DISPLAY INVISIBLE (3102 2575);
FORCEADD TAP..1
R 2
(3100 2725);
FORCEPROP 3 LASTPIN (3150 2725) SIG_NAME P5E_CPU1_G1_TX_C_DN<4>
J 0
(3160 2735);
DISPLAY 0.659574 (3160 2735);
PAINT MONO (3160 2735);
DISPLAY INVISIBLE (3160 2735);
FORCEPROP 1 LASTPIN (3150 2725) BN 4
J 2
(3162 2733);
DISPLAY 0.680851 (3162 2733);
PAINT GREEN (3162 2733);
FORCEPROP 2 LAST CDS_LIB standard
J 0
(3100 2725);
PAINT MONO (3100 2725);
DISPLAY INVISIBLE (3100 2725);
FORCEPROP 1 LAST BODY_TYPE PLUMBING
J 2
(3100 2775);
DISPLAY 0.872340 (3100 2775);
PAINT GREEN (3100 2775);
DISPLAY INVISIBLE (3100 2775);
FORCEPROP 1 LAST HDL_TAP TRUE
J 2
(2775 2600);
DISPLAY 0.872340 (2775 2600);
PAINT GREEN (2775 2600);
DISPLAY INVISIBLE (2775 2600);
FORCEPROP 1 LAST PATH I73
J 2
(3102 2725);
DISPLAY 0.872340 (3102 2725);
PAINT GREEN (3102 2725);
DISPLAY INVISIBLE (3102 2725);
FORCEADD TAP..1
R 2
(3250 2625);
FORCEPROP 3 LASTPIN (3300 2625) SIG_NAME P5E_CPU1_G1_TX_C_DP<5>
J 0
(3310 2635);
DISPLAY 0.659574 (3310 2635);
PAINT MONO (3310 2635);
DISPLAY INVISIBLE (3310 2635);
FORCEPROP 1 LASTPIN (3300 2625) BN 5
J 2
(3312 2633);
DISPLAY 0.680851 (3312 2633);
PAINT GREEN (3312 2633);
FORCEPROP 2 LAST CDS_LIB standard
J 0
(3250 2625);
PAINT MONO (3250 2625);
DISPLAY INVISIBLE (3250 2625);
FORCEPROP 1 LAST BODY_TYPE PLUMBING
J 2
(3250 2675);
DISPLAY 0.872340 (3250 2675);
PAINT GREEN (3250 2675);
DISPLAY INVISIBLE (3250 2675);
FORCEPROP 1 LAST HDL_TAP TRUE
J 2
(2925 2500);
DISPLAY 0.872340 (2925 2500);
PAINT GREEN (2925 2500);
DISPLAY INVISIBLE (2925 2500);
FORCEPROP 1 LAST PATH I74
J 2
(3252 2625);
DISPLAY 0.872340 (3252 2625);
PAINT GREEN (3252 2625);
DISPLAY INVISIBLE (3252 2625);
FORCEADD TAP..1
R 2
(3250 2775);
FORCEPROP 3 LASTPIN (3300 2775) SIG_NAME P5E_CPU1_G1_TX_C_DP<4>
J 0
(3310 2785);
DISPLAY 0.659574 (3310 2785);
PAINT MONO (3310 2785);
DISPLAY INVISIBLE (3310 2785);
FORCEPROP 1 LASTPIN (3300 2775) BN 4
J 2
(3312 2783);
DISPLAY 0.680851 (3312 2783);
PAINT GREEN (3312 2783);
FORCEPROP 2 LAST CDS_LIB standard
J 0
(3250 2775);
PAINT MONO (3250 2775);
DISPLAY INVISIBLE (3250 2775);
FORCEPROP 1 LAST BODY_TYPE PLUMBING
J 2
(3250 2825);
DISPLAY 0.872340 (3250 2825);
PAINT GREEN (3250 2825);
DISPLAY INVISIBLE (3250 2825);
FORCEPROP 1 LAST HDL_TAP TRUE
J 2
(2925 2650);
DISPLAY 0.872340 (2925 2650);
PAINT GREEN (2925 2650);
DISPLAY INVISIBLE (2925 2650);
FORCEPROP 1 LAST PATH I75
J 2
(3252 2775);
DISPLAY 0.872340 (3252 2775);
PAINT GREEN (3252 2775);
DISPLAY INVISIBLE (3252 2775);
FORCEADD TAP..1
R 2
(3100 3025);
FORCEPROP 3 LASTPIN (3150 3025) SIG_NAME P5E_CPU1_G1_TX_C_DN<3>
J 0
(3160 3035);
DISPLAY 0.659574 (3160 3035);
PAINT MONO (3160 3035);
DISPLAY INVISIBLE (3160 3035);
FORCEPROP 1 LASTPIN (3150 3025) BN 3
J 2
(3162 3033);
DISPLAY 0.680851 (3162 3033);
PAINT GREEN (3162 3033);
FORCEPROP 2 LAST CDS_LIB standard
J 0
(3100 3025);
PAINT MONO (3100 3025);
DISPLAY INVISIBLE (3100 3025);
FORCEPROP 1 LAST BODY_TYPE PLUMBING
J 2
(3100 3075);
DISPLAY 0.872340 (3100 3075);
PAINT GREEN (3100 3075);
DISPLAY INVISIBLE (3100 3075);
FORCEPROP 1 LAST HDL_TAP TRUE
J 2
(2775 2900);
DISPLAY 0.872340 (2775 2900);
PAINT GREEN (2775 2900);
DISPLAY INVISIBLE (2775 2900);
FORCEPROP 1 LAST PATH I76
J 2
(3102 3025);
DISPLAY 0.872340 (3102 3025);
PAINT GREEN (3102 3025);
DISPLAY INVISIBLE (3102 3025);
FORCEADD TAP..1
R 2
(3100 3175);
FORCEPROP 3 LASTPIN (3150 3175) SIG_NAME P5E_CPU1_G1_TX_C_DN<2>
J 0
(3160 3185);
DISPLAY 0.659574 (3160 3185);
PAINT MONO (3160 3185);
DISPLAY INVISIBLE (3160 3185);
FORCEPROP 1 LASTPIN (3150 3175) BN 2
J 2
(3162 3183);
DISPLAY 0.680851 (3162 3183);
PAINT GREEN (3162 3183);
FORCEPROP 2 LAST CDS_LIB standard
J 0
(3100 3175);
PAINT MONO (3100 3175);
DISPLAY INVISIBLE (3100 3175);
FORCEPROP 1 LAST BODY_TYPE PLUMBING
J 2
(3100 3225);
DISPLAY 0.872340 (3100 3225);
PAINT GREEN (3100 3225);
DISPLAY INVISIBLE (3100 3225);
FORCEPROP 1 LAST HDL_TAP TRUE
J 2
(2775 3050);
DISPLAY 0.872340 (2775 3050);
PAINT GREEN (2775 3050);
DISPLAY INVISIBLE (2775 3050);
FORCEPROP 1 LAST PATH I77
J 2
(3102 3175);
DISPLAY 0.872340 (3102 3175);
PAINT GREEN (3102 3175);
DISPLAY INVISIBLE (3102 3175);
FORCEADD TAP..1
R 2
(3250 3075);
FORCEPROP 3 LASTPIN (3300 3075) SIG_NAME P5E_CPU1_G1_TX_C_DP<3>
J 0
(3310 3085);
DISPLAY 0.659574 (3310 3085);
PAINT MONO (3310 3085);
DISPLAY INVISIBLE (3310 3085);
FORCEPROP 1 LASTPIN (3300 3075) BN 3
J 2
(3312 3083);
DISPLAY 0.680851 (3312 3083);
PAINT GREEN (3312 3083);
FORCEPROP 2 LAST CDS_LIB standard
J 0
(3250 3075);
PAINT MONO (3250 3075);
DISPLAY INVISIBLE (3250 3075);
FORCEPROP 1 LAST BODY_TYPE PLUMBING
J 2
(3250 3125);
DISPLAY 0.872340 (3250 3125);
PAINT GREEN (3250 3125);
DISPLAY INVISIBLE (3250 3125);
FORCEPROP 1 LAST HDL_TAP TRUE
J 2
(2925 2950);
DISPLAY 0.872340 (2925 2950);
PAINT GREEN (2925 2950);
DISPLAY INVISIBLE (2925 2950);
FORCEPROP 1 LAST PATH I78
J 2
(3252 3075);
DISPLAY 0.872340 (3252 3075);
PAINT GREEN (3252 3075);
DISPLAY INVISIBLE (3252 3075);
FORCEADD TAP..1
R 2
(3250 3225);
FORCEPROP 3 LASTPIN (3300 3225) SIG_NAME P5E_CPU1_G1_TX_C_DP<2>
J 0
(3310 3235);
DISPLAY 0.659574 (3310 3235);
PAINT MONO (3310 3235);
DISPLAY INVISIBLE (3310 3235);
FORCEPROP 1 LASTPIN (3300 3225) BN 2
J 2
(3312 3233);
DISPLAY 0.680851 (3312 3233);
PAINT GREEN (3312 3233);
FORCEPROP 2 LAST CDS_LIB standard
J 0
(3250 3225);
PAINT MONO (3250 3225);
DISPLAY INVISIBLE (3250 3225);
FORCEPROP 1 LAST BODY_TYPE PLUMBING
J 2
(3250 3275);
DISPLAY 0.872340 (3250 3275);
PAINT GREEN (3250 3275);
DISPLAY INVISIBLE (3250 3275);
FORCEPROP 1 LAST HDL_TAP TRUE
J 2
(2925 3100);
DISPLAY 0.872340 (2925 3100);
PAINT GREEN (2925 3100);
DISPLAY INVISIBLE (2925 3100);
FORCEPROP 1 LAST PATH I79
J 2
(3252 3225);
DISPLAY 0.872340 (3252 3225);
PAINT GREEN (3252 3225);
DISPLAY INVISIBLE (3252 3225);
FORCEADD OFFPAGE..5
(2400 -100);
FORCEPROP 2 LAST $XR1 137 
J 0
(2056 -100);
DISPLAY 0.638298 (2056 -100);
PAINT MONO (2056 -100);
FORCEPROP 2 LAST $XR0 80 
J 0
(2176 -100);
DISPLAY 0.638298 (2176 -100);
PAINT MONO (2176 -100);
FORCEPROP 2 LAST CDS_LIB standard
J 0
(2400 -100);
PAINT MONO (2400 -100);
DISPLAY INVISIBLE (2400 -100);
FORCEPROP 1 LAST OFFPAGE TRUE
J 0
(2725 -225);
DISPLAY 0.872340 (2725 -225);
PAINT GREEN (2725 -225);
DISPLAY INVISIBLE (2725 -225);
FORCEPROP 1 LAST COMMENT_BODY TRUE
J 0
(2500 -175);
DISPLAY 0.872340 (2500 -175);
PAINT GREEN (2500 -175);
DISPLAY INVISIBLE (2500 -175);
FORCEPROP 2 LAST PATH I8
J 0
(2125 -50);
DISPLAY 0.680851 (2125 -50);
DISPLAY INVISIBLE (2125 -50);
FORCEADD TAP..1
R 2
(3100 3325);
FORCEPROP 3 LASTPIN (3150 3325) SIG_NAME P5E_CPU1_G1_TX_C_DN<1>
J 0
(3160 3335);
DISPLAY 0.659574 (3160 3335);
PAINT MONO (3160 3335);
DISPLAY INVISIBLE (3160 3335);
FORCEPROP 1 LASTPIN (3150 3325) BN 1
J 2
(3162 3333);
DISPLAY 0.680851 (3162 3333);
PAINT GREEN (3162 3333);
FORCEPROP 2 LAST CDS_LIB standard
J 0
(3100 3325);
PAINT MONO (3100 3325);
DISPLAY INVISIBLE (3100 3325);
FORCEPROP 1 LAST BODY_TYPE PLUMBING
J 2
(3100 3375);
DISPLAY 0.872340 (3100 3375);
PAINT GREEN (3100 3375);
DISPLAY INVISIBLE (3100 3375);
FORCEPROP 1 LAST HDL_TAP TRUE
J 2
(2775 3200);
DISPLAY 0.872340 (2775 3200);
PAINT GREEN (2775 3200);
DISPLAY INVISIBLE (2775 3200);
FORCEPROP 1 LAST PATH I80
J 2
(3102 3325);
DISPLAY 0.872340 (3102 3325);
PAINT GREEN (3102 3325);
DISPLAY INVISIBLE (3102 3325);
FORCEADD TAP..1
R 2
(3100 3475);
FORCEPROP 3 LASTPIN (3150 3475) SIG_NAME P5E_CPU1_G1_TX_C_DN<0>
J 0
(3160 3485);
DISPLAY 0.659574 (3160 3485);
PAINT MONO (3160 3485);
DISPLAY INVISIBLE (3160 3485);
FORCEPROP 1 LASTPIN (3150 3475) BN 0
J 2
(3162 3483);
DISPLAY 0.680851 (3162 3483);
PAINT GREEN (3162 3483);
FORCEPROP 2 LAST CDS_LIB standard
J 0
(3100 3475);
DISPLAY INVISIBLE (3100 3475);
FORCEPROP 1 LAST BODY_TYPE PLUMBING
J 2
(3100 3525);
DISPLAY 0.872340 (3100 3525);
PAINT GREEN (3100 3525);
DISPLAY INVISIBLE (3100 3525);
FORCEPROP 1 LAST HDL_TAP TRUE
J 2
(2775 3350);
DISPLAY 0.872340 (2775 3350);
PAINT GREEN (2775 3350);
DISPLAY INVISIBLE (2775 3350);
FORCEPROP 1 LAST PATH I81
J 2
(3102 3475);
DISPLAY 0.872340 (3102 3475);
PAINT GREEN (3102 3475);
DISPLAY INVISIBLE (3102 3475);
FORCEADD TAP..1
R 2
(3250 3525);
FORCEPROP 3 LASTPIN (3300 3525) SIG_NAME P5E_CPU1_G1_TX_C_DP<0>
J 0
(3310 3535);
DISPLAY 0.659574 (3310 3535);
PAINT MONO (3310 3535);
DISPLAY INVISIBLE (3310 3535);
FORCEPROP 1 LASTPIN (3300 3525) BN 0
J 2
(3312 3533);
DISPLAY 0.680851 (3312 3533);
PAINT GREEN (3312 3533);
FORCEPROP 2 LAST CDS_LIB standard
J 0
(3250 3525);
DISPLAY INVISIBLE (3250 3525);
FORCEPROP 1 LAST BODY_TYPE PLUMBING
J 2
(3250 3575);
DISPLAY 0.872340 (3250 3575);
PAINT GREEN (3250 3575);
DISPLAY INVISIBLE (3250 3575);
FORCEPROP 1 LAST HDL_TAP TRUE
J 2
(2925 3400);
DISPLAY 0.872340 (2925 3400);
PAINT GREEN (2925 3400);
DISPLAY INVISIBLE (2925 3400);
FORCEPROP 1 LAST PATH I82
J 2
(3252 3525);
DISPLAY 0.872340 (3252 3525);
PAINT GREEN (3252 3525);
DISPLAY INVISIBLE (3252 3525);
FORCEADD TAP..1
R 2
(3250 3375);
FORCEPROP 3 LASTPIN (3300 3375) SIG_NAME P5E_CPU1_G1_TX_C_DP<1>
J 0
(3310 3385);
DISPLAY 0.659574 (3310 3385);
PAINT MONO (3310 3385);
DISPLAY INVISIBLE (3310 3385);
FORCEPROP 1 LASTPIN (3300 3375) BN 1
J 2
(3312 3383);
DISPLAY 0.680851 (3312 3383);
PAINT GREEN (3312 3383);
FORCEPROP 2 LAST CDS_LIB standard
J 0
(3250 3375);
PAINT MONO (3250 3375);
DISPLAY INVISIBLE (3250 3375);
FORCEPROP 1 LAST BODY_TYPE PLUMBING
J 2
(3250 3425);
DISPLAY 0.872340 (3250 3425);
PAINT GREEN (3250 3425);
DISPLAY INVISIBLE (3250 3425);
FORCEPROP 1 LAST HDL_TAP TRUE
J 2
(2925 3250);
DISPLAY 0.872340 (2925 3250);
PAINT GREEN (2925 3250);
DISPLAY INVISIBLE (2925 3250);
FORCEPROP 1 LAST PATH I83
J 2
(3252 3375);
DISPLAY 0.872340 (3252 3375);
PAINT GREEN (3252 3375);
DISPLAY INVISIBLE (3252 3375);
FORCEADD OFFPAGE..4
R 2
(775 5075);
FORCEPROP 2 LAST $XR1 137 
J 0
(404 5075);
DISPLAY 0.638298 (404 5075);
PAINT MONO (404 5075);
FORCEPROP 2 LAST $XR0 80 
J 0
(524 5075);
DISPLAY 0.638298 (524 5075);
PAINT MONO (524 5075);
FORCEPROP 2 LAST CDS_LIB standard
J 2
(775 5075);
DISPLAY INVISIBLE (775 5075);
FORCEPROP 1 LAST OFFPAGE TRUE
J 2
(450 4950);
DISPLAY 0.872340 (450 4950);
DISPLAY INVISIBLE (450 4950);
FORCEPROP 1 LAST COMMENT_BODY TRUE
J 2
(800 4975);
DISPLAY 0.872340 (800 4975);
PAINT GREEN (800 4975);
DISPLAY INVISIBLE (800 4975);
FORCEPROP 2 LAST PATH I84
J 2
(1025 5125);
DISPLAY 0.680851 (1025 5125);
DISPLAY INVISIBLE (1025 5125);
FORCEADD OFFPAGE..5
(775 5125);
FORCEPROP 2 LAST $XR2 138 
J 0
(310 5125);
DISPLAY 0.638298 (310 5125);
PAINT MONO (310 5125);
FORCEPROP 2 LAST $XR1 80 
J 0
(430 5125);
DISPLAY 0.638298 (430 5125);
PAINT MONO (430 5125);
FORCEPROP 2 LAST $XR0 137 
J 0
(520 5125);
DISPLAY 0.638298 (520 5125);
PAINT MONO (520 5125);
FORCEPROP 2 LAST CDS_LIB standard
J 0
(775 5125);
DISPLAY INVISIBLE (775 5125);
FORCEPROP 1 LAST OFFPAGE TRUE
J 0
(1100 5000);
DISPLAY 0.872340 (1100 5000);
PAINT GREEN (1100 5000);
DISPLAY INVISIBLE (1100 5000);
FORCEPROP 1 LAST COMMENT_BODY TRUE
J 0
(875 5050);
DISPLAY 0.872340 (875 5050);
PAINT GREEN (875 5050);
DISPLAY INVISIBLE (875 5050);
FORCEPROP 2 LAST PATH I85
J 0
(525 5175);
DISPLAY 0.680851 (525 5175);
DISPLAY INVISIBLE (525 5175);
FORCEADD Q_RES..1
(1950 5075);
FORCEPROP 1 LAST LOCATION R3168
J 0
(1725 5075);
DISPLAY 0.638298 (1725 5075);
FORCEPROP 2 LAST $SEC 1
J 0
(1900 5275);
DISPLAY 0.680851 (1900 5275);
PAINT MONO (1900 5275);
DISPLAY INVISIBLE (1900 5275);
FORCEPROP 2 LAST CDS_SEC 1
J 0
(1900 5275);
DISPLAY 1.021277 (1900 5275);
DISPLAY INVISIBLE (1900 5275);
FORCEPROP 1 LASTPIN (1850 5075) $PN 1
J 0
(1862 5087);
DISPLAY 0.787234 (1862 5087);
FORCEPROP 1 LASTPIN (2050 5075) $PN 2
J 0
(2012 5087);
DISPLAY 0.787234 (2012 5087);
FORCEPROP 1 LAST TOLERANCE 5%
J 0
(2150 5075);
DISPLAY 0.638298 (2150 5075);
FORCEPROP 1 LAST VALUE 0
J 2
(2125 5075);
DISPLAY 0.638298 (2125 5075);
FORCEPROP 1 LAST PACK_TYPE 0402LF
J 0
(2225 5075);
DISPLAY 0.638298 (2225 5075);
FORCEPROP 1 LAST MATERIAL CHIP
J 0
(1825 5200);
DISPLAY 0.638298 (1825 5200);
DISPLAY INVISIBLE (1825 5200);
FORCEPROP 1 LAST WATTAGE 1/16W
J 2
(2125 5200);
DISPLAY 0.638298 (2125 5200);
DISPLAY INVISIBLE (2125 5200);
FORCEPROP 2 LAST CDS_LIB pure_quanta
J 0
(1950 5075);
PAINT MONO (1950 5075);
DISPLAY INVISIBLE (1950 5075);
FORCEPROP 1 LAST PATH I86
J 0
(1900 5225);
DISPLAY 0.978723 (1900 5225);
PAINT WHITE (1900 5225);
DISPLAY INVISIBLE (1900 5225);
FORCEPROP 1 LAST PART_NUMBER CS00002JB13
J 0
(1825 5150);
DISPLAY 0.638298 (1825 5150);
DISPLAY INVISIBLE (1825 5150);
FORCEADD OFFPAGE..5
(2500 4475);
FORCEPROP 2 LAST $XR0 138 
J 0
(2245 4475);
DISPLAY 0.638298 (2245 4475);
PAINT MONO (2245 4475);
FORCEPROP 2 LAST CDS_LIB standard
J 0
(2500 4475);
PAINT MONO (2500 4475);
DISPLAY INVISIBLE (2500 4475);
FORCEPROP 1 LAST OFFPAGE TRUE
J 0
(2825 4350);
DISPLAY 0.872340 (2825 4350);
PAINT GREEN (2825 4350);
DISPLAY INVISIBLE (2825 4350);
FORCEPROP 1 LAST COMMENT_BODY TRUE
J 0
(2600 4400);
DISPLAY 0.872340 (2600 4400);
PAINT GREEN (2600 4400);
DISPLAY INVISIBLE (2600 4400);
FORCEPROP 2 LAST PATH I87
J 0
(2250 4525);
DISPLAY 0.680851 (2250 4525);
DISPLAY INVISIBLE (2250 4525);
FORCEADD OFFPAGE..1
(2500 4575);
FORCEPROP 2 LAST $XR0 55 
J 0
(2249 4575);
DISPLAY 0.638298 (2249 4575);
PAINT MONO (2249 4575);
FORCEPROP 2 LAST CDS_LIB standard
J 0
(2500 4575);
PAINT MONO (2500 4575);
DISPLAY INVISIBLE (2500 4575);
FORCEPROP 1 LAST OFFPAGE TRUE
J 0
(2825 4450);
DISPLAY 0.872340 (2825 4450);
PAINT GREEN (2825 4450);
DISPLAY INVISIBLE (2825 4450);
FORCEPROP 1 LAST COMMENT_BODY TRUE
J 0
(2625 4475);
DISPLAY 0.872340 (2625 4475);
PAINT GREEN (2625 4475);
DISPLAY INVISIBLE (2625 4475);
FORCEPROP 2 LAST PATH I88
J 0
(2250 4625);
DISPLAY 0.680851 (2250 4625);
DISPLAY INVISIBLE (2250 4625);
FORCEADD OFFPAGE..1
(2500 4625);
FORCEPROP 2 LAST $XR0 55 
J 0
(2249 4625);
DISPLAY 0.638298 (2249 4625);
PAINT MONO (2249 4625);
FORCEPROP 2 LAST CDS_LIB standard
J 0
(2500 4625);
PAINT MONO (2500 4625);
DISPLAY INVISIBLE (2500 4625);
FORCEPROP 1 LAST OFFPAGE TRUE
J 0
(2825 4500);
DISPLAY 0.872340 (2825 4500);
PAINT GREEN (2825 4500);
DISPLAY INVISIBLE (2825 4500);
FORCEPROP 1 LAST COMMENT_BODY TRUE
J 0
(2625 4525);
DISPLAY 0.872340 (2625 4525);
PAINT GREEN (2625 4525);
DISPLAY INVISIBLE (2625 4525);
FORCEPROP 2 LAST PATH I89
J 0
(2250 4675);
DISPLAY 0.680851 (2250 4675);
DISPLAY INVISIBLE (2250 4675);
FORCEADD Q_RES..1
(3650 -275);
FORCEPROP 1 LAST LOCATION R3174
J 0
(3450 -275);
DISPLAY 0.638298 (3450 -275);
FORCEPROP 0 LAST $SEC 1
J 0
(3450 -225);
DISPLAY 0.680851 (3450 -225);
PAINT MONO (3450 -225);
DISPLAY INVISIBLE (3450 -225);
FORCEPROP 0 LAST CDS_SEC 1
J 0
(3450 -225);
DISPLAY 1.021277 (3450 -225);
DISPLAY INVISIBLE (3450 -225);
FORCEPROP 1 LASTPIN (3550 -275) $PN 1
J 0
(3562 -263);
DISPLAY 0.787234 (3562 -263);
PAINT MONO (3562 -263);
FORCEPROP 1 LASTPIN (3750 -275) $PN 2
J 0
(3712 -263);
DISPLAY 0.787234 (3712 -263);
PAINT MONO (3712 -263);
FORCEPROP 1 LAST TOLERANCE 1%
J 0
(3850 -275);
DISPLAY 0.510638 (3850 -275);
FORCEPROP 1 LAST VALUE 10K
J 2
(3825 -275);
DISPLAY 0.510638 (3825 -275);
FORCEPROP 1 LAST MATERIAL CHIP
J 0
(3925 -275);
DISPLAY 0.510638 (3925 -275);
FORCEPROP 1 LAST WATTAGE 1/16W
J 2
(3850 -150);
DISPLAY 0.510638 (3850 -150);
DISPLAY INVISIBLE (3850 -150);
FORCEPROP 1 LAST PACK_TYPE 0402LF
J 0
(3475 -150);
DISPLAY 0.510638 (3475 -150);
DISPLAY INVISIBLE (3475 -150);
FORCEPROP 2 LAST CDS_LIB pure_quanta
J 0
(3650 -275);
DISPLAY INVISIBLE (3650 -275);
FORCEPROP 1 LAST PATH I9
J 0
(3600 -125);
DISPLAY 0.978723 (3600 -125);
PAINT WHITE (3600 -125);
DISPLAY INVISIBLE (3600 -125);
FORCEPROP 1 LAST PART_NUMBER CS31002FB08
J 0
(3475 -200);
DISPLAY 0.510638 (3475 -200);
DISPLAY INVISIBLE (3475 -200);
FORCEADD OFFPAGE..5
(2500 4775);
FORCEPROP 2 LAST $XR0 138 
J 0
(2245 4775);
DISPLAY 0.638298 (2245 4775);
PAINT MONO (2245 4775);
FORCEPROP 2 LAST CDS_LIB standard
J 0
(2500 4775);
PAINT MONO (2500 4775);
DISPLAY INVISIBLE (2500 4775);
FORCEPROP 1 LAST OFFPAGE TRUE
J 0
(2825 4650);
DISPLAY 0.872340 (2825 4650);
PAINT GREEN (2825 4650);
DISPLAY INVISIBLE (2825 4650);
FORCEPROP 1 LAST COMMENT_BODY TRUE
J 0
(2600 4700);
DISPLAY 0.872340 (2600 4700);
PAINT GREEN (2600 4700);
DISPLAY INVISIBLE (2600 4700);
FORCEPROP 2 LAST PATH I90
J 0
(2250 4825);
DISPLAY 0.680851 (2250 4825);
DISPLAY INVISIBLE (2250 4825);
FORCEADD OFFPAGE..5
(2500 4725);
FORCEPROP 2 LAST $XR0 138 
J 0
(2245 4725);
DISPLAY 0.638298 (2245 4725);
PAINT MONO (2245 4725);
FORCEPROP 2 LAST CDS_LIB standard
J 0
(2500 4725);
PAINT MONO (2500 4725);
DISPLAY INVISIBLE (2500 4725);
FORCEPROP 1 LAST OFFPAGE TRUE
J 0
(2825 4600);
DISPLAY 0.872340 (2825 4600);
PAINT GREEN (2825 4600);
DISPLAY INVISIBLE (2825 4600);
FORCEPROP 1 LAST COMMENT_BODY TRUE
J 0
(2600 4650);
DISPLAY 0.872340 (2600 4650);
PAINT GREEN (2600 4650);
DISPLAY INVISIBLE (2600 4650);
FORCEPROP 2 LAST PATH I91
J 0
(2250 4775);
DISPLAY 0.680851 (2250 4775);
DISPLAY INVISIBLE (2250 4775);
FORCEADD OFFPAGE..1
(2500 4825);
FORCEPROP 2 LAST $XR0 137 
J 0
(2248 4825);
DISPLAY 0.638298 (2248 4825);
PAINT MONO (2248 4825);
FORCEPROP 2 LAST CDS_LIB standard
J 0
(2500 4825);
PAINT MONO (2500 4825);
DISPLAY INVISIBLE (2500 4825);
FORCEPROP 1 LAST OFFPAGE TRUE
J 0
(2825 4700);
DISPLAY 0.872340 (2825 4700);
PAINT GREEN (2825 4700);
DISPLAY INVISIBLE (2825 4700);
FORCEPROP 1 LAST COMMENT_BODY TRUE
J 0
(2625 4725);
DISPLAY 0.872340 (2625 4725);
PAINT GREEN (2625 4725);
DISPLAY INVISIBLE (2625 4725);
FORCEPROP 2 LAST PATH I92
J 0
(2250 4875);
DISPLAY 0.680851 (2250 4875);
DISPLAY INVISIBLE (2250 4875);
FORCEADD OFFPAGE..5
(2500 4875);
FORCEPROP 2 LAST $XR1 80 
J 0
(2155 4875);
DISPLAY 0.638298 (2155 4875);
PAINT MONO (2155 4875);
FORCEPROP 2 LAST $XR0 137 
J 0
(2245 4875);
DISPLAY 0.638298 (2245 4875);
PAINT MONO (2245 4875);
FORCEPROP 2 LAST CDS_LIB standard
J 0
(2500 4875);
PAINT MONO (2500 4875);
DISPLAY INVISIBLE (2500 4875);
FORCEPROP 1 LAST OFFPAGE TRUE
J 0
(2825 4750);
DISPLAY 0.872340 (2825 4750);
PAINT GREEN (2825 4750);
DISPLAY INVISIBLE (2825 4750);
FORCEPROP 1 LAST COMMENT_BODY TRUE
J 0
(2600 4800);
DISPLAY 0.872340 (2600 4800);
PAINT GREEN (2600 4800);
DISPLAY INVISIBLE (2600 4800);
FORCEPROP 2 LAST PATH I93
J 0
(2250 4925);
DISPLAY 0.680851 (2250 4925);
DISPLAY INVISIBLE (2250 4925);
FORCEADD OFFPAGE..1
(2500 4925);
FORCEPROP 2 LAST $XR1 137 
J 0
(2129 4925);
DISPLAY 0.638298 (2129 4925);
PAINT MONO (2129 4925);
FORCEPROP 2 LAST $XR0 80 
J 0
(2249 4925);
DISPLAY 0.638298 (2249 4925);
PAINT MONO (2249 4925);
FORCEPROP 2 LAST CDS_LIB standard
J 0
(2500 4925);
PAINT MONO (2500 4925);
DISPLAY INVISIBLE (2500 4925);
FORCEPROP 1 LAST OFFPAGE TRUE
J 0
(2825 4800);
DISPLAY 0.872340 (2825 4800);
PAINT GREEN (2825 4800);
DISPLAY INVISIBLE (2825 4800);
FORCEPROP 1 LAST COMMENT_BODY TRUE
J 0
(2625 4825);
DISPLAY 0.872340 (2625 4825);
PAINT GREEN (2625 4825);
DISPLAY INVISIBLE (2625 4825);
FORCEPROP 2 LAST PATH I94
J 0
(2250 4975);
DISPLAY 0.680851 (2250 4975);
DISPLAY INVISIBLE (2250 4975);
FORCEADD OFFPAGE..1
(2500 5025);
FORCEPROP 2 LAST $XR1 137 
J 0
(2129 5025);
DISPLAY 0.638298 (2129 5025);
PAINT MONO (2129 5025);
FORCEPROP 2 LAST $XR0 80 
J 0
(2249 5025);
DISPLAY 0.638298 (2249 5025);
PAINT MONO (2249 5025);
FORCEPROP 2 LAST CDS_LIB standard
J 0
(2500 5025);
PAINT MONO (2500 5025);
DISPLAY INVISIBLE (2500 5025);
FORCEPROP 1 LAST OFFPAGE TRUE
J 0
(2825 4900);
DISPLAY 0.872340 (2825 4900);
PAINT GREEN (2825 4900);
DISPLAY INVISIBLE (2825 4900);
FORCEPROP 1 LAST COMMENT_BODY TRUE
J 0
(2625 4925);
DISPLAY 0.872340 (2625 4925);
PAINT GREEN (2625 4925);
DISPLAY INVISIBLE (2625 4925);
FORCEPROP 2 LAST PATH I95
J 0
(2250 5075);
DISPLAY 0.680851 (2250 5075);
DISPLAY INVISIBLE (2250 5075);
FORCEADD OFFPAGE..1
(2500 4975);
FORCEPROP 2 LAST $XR1 137 
J 0
(2129 4975);
DISPLAY 0.638298 (2129 4975);
PAINT MONO (2129 4975);
FORCEPROP 2 LAST $XR0 80 
J 0
(2249 4975);
DISPLAY 0.638298 (2249 4975);
PAINT MONO (2249 4975);
FORCEPROP 2 LAST CDS_LIB standard
J 0
(2500 4975);
PAINT MONO (2500 4975);
DISPLAY INVISIBLE (2500 4975);
FORCEPROP 1 LAST OFFPAGE TRUE
J 0
(2825 4850);
DISPLAY 0.872340 (2825 4850);
PAINT GREEN (2825 4850);
DISPLAY INVISIBLE (2825 4850);
FORCEPROP 1 LAST COMMENT_BODY TRUE
J 0
(2625 4875);
DISPLAY 0.872340 (2625 4875);
PAINT GREEN (2625 4875);
DISPLAY INVISIBLE (2625 4875);
FORCEPROP 2 LAST PATH I96
J 0
(2250 5025);
DISPLAY 0.680851 (2250 5025);
DISPLAY INVISIBLE (2250 5025);
FORCEADD UNIVERSAL_POWER..1
(2550 4225);
FORCEPROP 3 LASTPIN (2550 4175) SIG_NAME P3V3_OCP_V3_2\g
J 0
(2560 4185);
DISPLAY 0.659574 (2560 4185);
PAINT MONO (2560 4185);
DISPLAY INVISIBLE (2560 4185);
FORCEPROP 1 LAST HDL_POWER P3V3_OCP_V3_2
J 1
(2550 4275);
DISPLAY 0.872340 (2550 4275);
PAINT GREEN (2550 4275);
FORCEPROP 2 LAST CDS_LIB pure_quanta_power
J 0
(2550 4225);
DISPLAY INVISIBLE (2550 4225);
FORCEPROP 1 LAST PATH I97
J 0
(2600 4250);
DISPLAY 0.872340 (2600 4250);
PAINT AQUA (2600 4250);
DISPLAY INVISIBLE (2600 4250);
FORCEADD UNIVERSAL_POWER..1
(3525 5450);
FORCEPROP 3 LASTPIN (3525 5400) SIG_NAME P12V_OCP_V3_2_R\g
J 0
(3535 5410);
DISPLAY 0.659574 (3535 5410);
PAINT MONO (3535 5410);
DISPLAY INVISIBLE (3535 5410);
FORCEPROP 1 LAST HDL_POWER P12V_OCP_V3_2_R
J 1
(3525 5500);
DISPLAY 0.872340 (3525 5500);
PAINT GREEN (3525 5500);
FORCEPROP 2 LAST CDS_LIB pure_quanta_power
J 0
(3525 5450);
DISPLAY INVISIBLE (3525 5450);
FORCEPROP 1 LAST PATH I98
J 0
(3575 5475);
DISPLAY 0.872340 (3575 5475);
PAINT AQUA (3575 5475);
DISPLAY INVISIBLE (3575 5475);
FORCEADD UNIVERSAL_POWER..1
(4200 50);
FORCEPROP 3 LASTPIN (4200 0) SIG_NAME P3V3_OCP_V3_2\g
J 0
(4210 10);
DISPLAY 0.659574 (4210 10);
PAINT MONO (4210 10);
DISPLAY INVISIBLE (4210 10);
FORCEPROP 1 LAST HDL_POWER P3V3_OCP_V3_2
J 1
(4200 100);
DISPLAY 0.872340 (4200 100);
PAINT GREEN (4200 100);
FORCEPROP 2 LAST CDS_LIB pure_quanta_power
J 0
(4200 50);
PAINT MONO (4200 50);
DISPLAY INVISIBLE (4200 50);
FORCEPROP 1 LAST PATH I99
J 0
(4250 75);
DISPLAY 0.872340 (4250 75);
PAINT AQUA (4250 75);
DISPLAY INVISIBLE (4250 75);
FORCEADD CAD_NOTE..1
(6325 100);
FORCEPROP 0 LAST S1 PLACE THE BULK CAPS CLOSE TO SLOT
J 0
(6175 -25);
DISPLAY 0.808511 (6175 -25);
PAINT WHITE (6175 -25);
FORCEPROP 2 LAST CDS_LIB pure_quanta_power
J 0
(6325 100);
PAINT MONO (6325 100);
DISPLAY INVISIBLE (6325 100);
FORCEPROP 1 LAST COMMENT_BODY TRUE
J 0
(6350 200);
DISPLAY 0.978723 (6350 200);
DISPLAY INVISIBLE (6350 200);
FORCEADD DNS..2
(275 -250);
PAINT RED (275 -250);
FORCEPROP 2 LAST CDS_LIB mstr_misc
J 0
(275 -250);
PAINT MONO (275 -250);
DISPLAY INVISIBLE (275 -250);
FORCEPROP 1 LAST COMMENT_BODY TRUE
R 1
J 0
(350 -475);
DISPLAY 0.872340 (350 -475);
PAINT GREEN (350 -475);
DISPLAY INVISIBLE (350 -475);
FORCEADD DNS..2
(750 275);
PAINT RED (750 275);
FORCEPROP 2 LAST CDS_LIB mstr_misc
J 0
(750 275);
PAINT MONO (750 275);
DISPLAY INVISIBLE (750 275);
FORCEPROP 1 LAST COMMENT_BODY TRUE
R 1
J 0
(825 50);
DISPLAY 0.872340 (825 50);
PAINT GREEN (825 50);
DISPLAY INVISIBLE (825 50);
FORCEADD QUANTA_TITLE_BLOCK_C..1
(9275 -900);
FORCEPROP 0 LAST CDS_CON_LAST_MODIFIED Thu Sep 14 16:12:25 2023
J 0
(7390 -885);
PAINT MONO (7390 -885);
DISPLAY INVISIBLE (7390 -885);
FORCEPROP 1 LAST CUSTOM_TXT_CDS <CON_LAST_MODIFIED>
J 0
(7390 -885);
DISPLAY 0.978723 (7390 -885);
FORCEPROP 2 LAST CUSTOM_TXT_CDS <XR_PAGE_TITLE>
J 0
(1385 4350);
DISPLAY 0.638298 (1385 4350);
PAINT PINK (1385 4350);
DISPLAY INVISIBLE (1385 4350);
FORCEPROP 2 LAST CUSTOM_TXT_CDS <Q_NUMBER>
J 0
(7872 -797);
DISPLAY 1.212766 (7872 -797);
FORCEPROP 2 LAST CUSTOM_TXT_CDS <Q_PROJ>
J 0
(6893 -798);
DISPLAY 1.212766 (6893 -798);
FORCEPROP 2 LAST CUSTOM_TXT_CDS <Q_REV>
J 0
(9091 -797);
DISPLAY 1.212766 (9091 -797);
FORCEPROP 2 LAST CUSTOM_TXT_CDS <CON_PAGE_NUM> OF <CON_TOTAL_PAGES>
J 0
(8829 -882);
DISPLAY 0.978723 (8829 -882);
FORCEPROP 2 LAST CUSTOM_TXT_CDS <NAME_2>
J 0
(6100 -850);
FORCEPROP 2 LAST CUSTOM_TXT_CDS <NAME_1>
J 0
(6100 -725);
FORCEPROP 1 LAST Q_TITLE PCIE - V3_2 OCP3.0_X16_CPU1 (1/3)
J 0
(0 -825);
DISPLAY 1.957447 (0 -825);
PAINT GREEN (0 -825);
FORCEPROP 2 LAST PAGE_BORDER TRUE
J 0
(1385 4350);
DISPLAY 0.638298 (1385 4350);
PAINT PINK (1385 4350);
DISPLAY INVISIBLE (1385 4350);
FORCEPROP 1 LAST CDS_LMAN_SYM_OUTLINE -9475,6775,100,-125
J 0
(9275 -900);
DISPLAY 0.468085 (9275 -900);
PAINT GREEN (9275 -900);
DISPLAY INVISIBLE (9275 -900);
FORCEPROP 2 LAST CDS_LIB pure_quanta
J 0
(9275 -900);
PAINT MONO (9275 -900);
DISPLAY INVISIBLE (9275 -900);
FORCEPROP 2 LAST CDS_XR_PAGE_TITLE CR-137 : @T6G_MB_LIB.T6G(SCH_1):PAGE137
J 0
(1385 4350);
DISPLAY 0.638298 (1385 4350);
PAINT PINK (1385 4350);
DISPLAY INVISIBLE (1385 4350);
FORCEPROP 1 LAST Q_DEPT BU9
J 1
(5512 -851);
DISPLAY 1.957447 (5512 -851);
PAINT GREEN (5512 -851);
DISPLAY INVISIBLE (5512 -851);
FORCEPROP 1 LAST COMMENT_BODY TRUE
J 0
(9287 -913);
DISPLAY 0.978723 (9287 -913);
PAINT GREEN (9287 -913);
DISPLAY INVISIBLE (9287 -913);
WIRE 17 -1 (5650 1500)(5650 1350);
WIRE 17 -1 (5650 1650)(5650 1500);
WIRE 17 -1 (5650 1350)(5650 1200);
WIRE 17 -1 (5650 1200)(5650 1050);
WIRE 17 -1 (5650 1650)(5650 1800);
WIRE 17 -1 (5650 1800)(5650 1950);
WIRE 17 -1 (5650 900)(5650 1050);
WIRE 17 -1 (5650 1950)(5650 2300);
WIRE 17 -1 (5650 2450)(5650 2300);
WIRE 17 -1 (5650 2450)(5650 2600);
WIRE 17 -1 (5650 2600)(5650 2750);
WIRE 17 -1 (5650 2750)(5650 3050);
WIRE 17 -1 (5650 3050)(5650 3200);
WIRE 17 -1 (5650 3350)(5650 3200);
WIRE 17 -1 (5650 3500)(5650 3350);
WIRE 17 -1 (6750 3500)(5650 3500);
FORCEPROP 2 LAST SIG_NAME P5E_CPU1_G1_RX_DP<15:0>
J 0
(5890 3510);
DISPLAY 0.638298 (5890 3510);
PAINT WHITE (5890 3510);
WIRE 17 -1 (5800 1550)(5800 1400);
WIRE 17 -1 (5800 1700)(5800 1550);
WIRE 17 -1 (5800 1400)(5800 1250);
WIRE 17 -1 (5800 1250)(5800 1100);
WIRE 17 -1 (5800 1700)(5800 1850);
WIRE 17 -1 (5800 1850)(5800 2000);
WIRE 17 -1 (5800 950)(5800 1100);
WIRE 17 -1 (5800 2000)(5800 2350);
WIRE 17 -1 (5800 2350)(5800 2500);
WIRE 17 -1 (5800 2500)(5800 2650);
WIRE 17 -1 (5800 2650)(5800 2800);
WIRE 17 -1 (5800 2800)(5800 3100);
WIRE 17 -1 (5800 3250)(5800 3100);
WIRE 17 -1 (5800 3400)(5800 3250);
WIRE 17 -1 (5800 3550)(5800 3400);
WIRE 17 -1 (6750 3550)(5800 3550);
FORCEPROP 2 LAST SIG_NAME P5E_CPU1_G1_RX_DN<15:0>
J 0
(5890 3560);
DISPLAY 0.638298 (5890 3560);
PAINT WHITE (5890 3560);
WIRE 17 -1 (3050 3200)(3050 3350);
WIRE 17 -1 (3050 3050)(3050 3200);
WIRE 17 -1 (3050 3350)(3050 3500);
WIRE 17 -1 (3050 3500)(2100 3500);
FORCEPROP 2 LAST SIG_NAME P5E_CPU1_G1_TX_C_DN<15:0>
J 0
(2140 3510);
DISPLAY 0.680851 (2140 3510);
PAINT WHITE (2140 3510);
WIRE 17 -1 (3200 3100)(3200 3250);
WIRE 17 -1 (3200 2800)(3200 3100);
WIRE 17 -1 (3200 3250)(3200 3400);
WIRE 17 -1 (3200 3400)(3200 3550);
WIRE 17 -1 (3200 2650)(3200 2800);
WIRE 17 -1 (3200 2500)(3200 2650);
WIRE 17 -1 (2100 3550)(3200 3550);
FORCEPROP 2 LAST SIG_NAME P5E_CPU1_G1_TX_C_DP<15:0>
J 0
(2140 3560);
DISPLAY 0.680851 (2140 3560);
PAINT WHITE (2140 3560);
WIRE 17 -1 (3050 2750)(3050 3050);
WIRE 17 -1 (3050 2600)(3050 2750);
WIRE 17 -1 (3050 2450)(3050 2600);
WIRE 17 -1 (3200 2350)(3200 2500);
WIRE 17 -1 (3050 2300)(3050 2450);
WIRE 17 -1 (3200 2000)(3200 2350);
WIRE 17 -1 (3200 1850)(3200 2000);
WIRE 17 -1 (3200 1700)(3200 1850);
WIRE 17 -1 (3050 1950)(3050 2300);
WIRE 17 -1 (3050 1800)(3050 1950);
WIRE 17 -1 (3050 1650)(3050 1800);
WIRE 17 -1 (3200 1700)(3200 1550);
WIRE 17 -1 (3050 1650)(3050 1500);
WIRE 17 -1 (3200 1550)(3200 1400);
WIRE 17 -1 (3200 1250)(3200 1400);
WIRE 17 -1 (3200 1100)(3200 1250);
WIRE 17 -1 (3050 1500)(3050 1350);
WIRE 17 -1 (3050 1200)(3050 1350);
WIRE 17 -1 (3050 1050)(3050 1200);
WIRE 17 -1 (3200 1100)(3200 950);
WIRE 17 -1 (3050 1050)(3050 900);
WIRE 16 -1 (275 -400)(275 -325);
WIRE 16 -1 (7950 3400)(7950 3525);
WIRE 16 -1 (750 -400)(750 -325);
WIRE 16 -1 (3825 3825)(2550 3825);
WIRE 16 -1 (2550 3825)(2550 4175);
WIRE 16 -1 (3825 4475)(2550 4475);
FORCEPROP 2 LAST SIG_NAME NCSI_OCP_V3_2_CRS_DV
J 0
(2615 4485);
DISPLAY 0.553191 (2615 4485);
PAINT WHITE (2615 4485);
WIRE 16 -1 (2550 4575)(3825 4575);
FORCEPROP 2 LAST SIG_NAME CLK_100M_CPU1_CLK04_DP
J 0
(2615 4585);
DISPLAY 0.553191 (2615 4585);
PAINT WHITE (2615 4585);
WIRE 16 -1 (2550 4625)(3825 4625);
FORCEPROP 2 LAST SIG_NAME CLK_100M_CPU1_CLK04_DN
J 0
(2615 4635);
DISPLAY 0.553191 (2615 4635);
PAINT WHITE (2615 4635);
WIRE 16 -1 (5125 4725)(6200 4725);
FORCEPROP 2 LAST SIG_NAME NCSI_OCP_V3_2_TXD0
J 0
(5415 4735);
DISPLAY 0.553191 (5415 4735);
PAINT WHITE (5415 4735);
WIRE 16 -1 (5125 4775)(6200 4775);
FORCEPROP 2 LAST SIG_NAME NCSI_OCP_V3_2_TXD1
J 0
(5415 4785);
DISPLAY 0.553191 (5415 4785);
PAINT WHITE (5415 4785);
WIRE 16 -1 (5125 4825)(6200 4825);
FORCEPROP 2 LAST SIG_NAME NCSI_OCP_V3_2_TX_EN
J 0
(5415 4835);
DISPLAY 0.553191 (5415 4835);
PAINT WHITE (5415 4835);
WIRE 16 -1 (5125 4875)(6200 4875);
FORCEPROP 2 LAST SIG_NAME OCP_V3_2_ID1
J 0
(5415 4885);
DISPLAY 0.553191 (5415 4885);
PAINT WHITE (5415 4885);
WIRE 16 -1 (5125 4925)(6200 4925);
FORCEPROP 2 LAST SIG_NAME OCP_V3_2_ISO2_RBT_ARB_OUT
J 0
(5415 4935);
DISPLAY 0.553191 (5415 4935);
PAINT WHITE (5415 4935);
WIRE 16 -1 (825 5125)(3825 5125);
FORCEPROP 2 LAST SIG_NAME FM_OCP_V3_2_PWR_GOOD
J 0
(2615 5135);
DISPLAY 0.553191 (2615 5135);
PAINT WHITE (2615 5135);
WIRE 16 -1 (5125 425)(5300 425);
WIRE 16 -1 (5300 475)(5300 425);
WIRE 16 -1 (5300 425)(5300 375);
WIRE 16 -1 (5125 375)(5300 375);
WIRE 16 -1 (5300 375)(5300 225);
WIRE 16 -1 (5300 525)(5300 475);
WIRE 16 -1 (5125 475)(5300 475);
WIRE 16 -1 (5300 575)(5300 525);
WIRE 16 -1 (5125 525)(5300 525);
WIRE 16 -1 (5300 825)(5300 575);
WIRE 16 -1 (5125 575)(5300 575);
WIRE 16 -1 (5300 975)(5300 825);
WIRE 16 -1 (5125 825)(5300 825);
WIRE 16 -1 (5300 1125)(5300 975);
WIRE 16 -1 (5125 975)(5300 975);
WIRE 16 -1 (5300 1275)(5300 1125);
WIRE 16 -1 (5125 1125)(5300 1125);
WIRE 16 -1 (5300 1425)(5300 1275);
WIRE 16 -1 (5125 1275)(5300 1275);
WIRE 16 -1 (5300 1575)(5300 1425);
WIRE 16 -1 (5125 1425)(5300 1425);
WIRE 16 -1 (5300 1725)(5300 1575);
WIRE 16 -1 (5125 1575)(5300 1575);
WIRE 16 -1 (5300 1875)(5300 1725);
WIRE 16 -1 (5125 1725)(5300 1725);
WIRE 16 -1 (5300 2025)(5300 1875);
WIRE 16 -1 (5125 1875)(5300 1875);
WIRE 16 -1 (5300 2225)(5300 2025);
WIRE 16 -1 (5125 2025)(5300 2025);
WIRE 16 -1 (5300 2375)(5300 2225);
WIRE 16 -1 (5125 2225)(5300 2225);
WIRE 16 -1 (5300 2525)(5300 2375);
WIRE 16 -1 (5125 2375)(5300 2375);
WIRE 16 -1 (5300 2675)(5300 2525);
WIRE 16 -1 (5125 2525)(5300 2525);
WIRE 16 -1 (5300 2825)(5300 2675);
WIRE 16 -1 (5125 2675)(5300 2675);
WIRE 16 -1 (5300 2975)(5300 2825);
WIRE 16 -1 (5125 2825)(5300 2825);
WIRE 16 -1 (5300 3125)(5300 2975);
WIRE 16 -1 (5125 2975)(5300 2975);
WIRE 16 -1 (5300 3275)(5300 3125);
WIRE 16 -1 (5125 3125)(5300 3125);
WIRE 16 -1 (5300 3425)(5300 3275);
WIRE 16 -1 (5125 3275)(5300 3275);
WIRE 16 -1 (5300 3575)(5300 3425);
WIRE 16 -1 (5125 3425)(5300 3425);
WIRE 16 -1 (5300 3725)(5300 3575);
WIRE 16 -1 (5125 3575)(5300 3575);
WIRE 16 -1 (5300 4075)(5300 3725);
WIRE 16 -1 (5125 3725)(5300 3725);
WIRE 16 -1 (5300 4125)(5300 4075);
WIRE 16 -1 (5125 4075)(5300 4075);
WIRE 16 -1 (5300 4175)(5300 4125);
WIRE 16 -1 (5125 4125)(5300 4125);
WIRE 16 -1 (5300 4225)(5300 4175);
WIRE 16 -1 (5125 4175)(5300 4175);
WIRE 16 -1 (5300 4275)(5300 4225);
WIRE 16 -1 (5125 4225)(5300 4225);
WIRE 16 -1 (5300 4325)(5300 4275);
WIRE 16 -1 (5125 4275)(5300 4275);
WIRE 16 -1 (5300 4525)(5300 4325);
WIRE 16 -1 (5125 4325)(5300 4325);
WIRE 16 -1 (5300 4675)(5300 4525);
WIRE 16 -1 (5125 4525)(5300 4525);
WIRE 16 -1 (5125 4675)(5300 4675);
WIRE 16 -1 (5125 4625)(6200 4625);
FORCEPROP 2 LAST SIG_NAME CLK_100M_CPU1_CLK05_DN
J 0
(5465 4635);
DISPLAY 0.553191 (5465 4635);
PAINT WHITE (5465 4635);
WIRE 16 -1 (5125 4575)(6200 4575);
FORCEPROP 2 LAST SIG_NAME CLK_100M_CPU1_CLK05_DP
J 0
(5465 4585);
DISPLAY 0.553191 (5465 4585);
PAINT WHITE (5465 4585);
WIRE 16 -1 (5125 4475)(6200 4475);
FORCEPROP 2 LAST SIG_NAME CLK_50M_NCSI_OCP_V3_2_ISO
J 0
(5415 4485);
DISPLAY 0.510638 (5415 4485);
PAINT WHITE (5415 4485);
WIRE 16 -1 (6275 4025)(5125 4025);
FORCEPROP 2 LAST SIG_NAME SMB_OCP_V3_2_3V3AUX_BUF_R_SCL
J 0
(5315 4035);
DISPLAY 0.553191 (5315 4035);
PAINT WHITE (5315 4035);
FORCEPROP 2 LASTPROP $XRERR UNIQUE?
J 0
(5075 4035);
DISPLAY 0.638298 (5075 4035);
PAINT MONO (5075 4035);
DISPLAY INVISIBLE (5075 4035);
WIRE 16 -1 (6475 4025)(7625 4025);
FORCEPROP 2 LAST SIG_NAME SMB_OCP_V3_2_3V3AUX_BUF_SCL
J 0
(6940 4035);
DISPLAY 0.553191 (6940 4035);
PAINT WHITE (6940 4035);
WIRE 16 -1 (7950 3725)(7950 3875);
WIRE 16 -1 (7950 3875)(5125 3875);
FORCEPROP 2 LAST SIG_NAME OCP_V3_2_PRSNTA_R_N
J 0
(5890 3885);
DISPLAY 0.510638 (5890 3885);
PAINT WHITE (5890 3885);
FORCEPROP 2 LASTPROP $XRERR UNIQUE?
J 0
(5650 3885);
DISPLAY 0.638298 (5650 3885);
PAINT MONO (5650 3885);
DISPLAY INVISIBLE (5650 3885);
WIRE 16 -1 (5125 3925)(7625 3925);
FORCEPROP 2 LAST SIG_NAME RST_SMB_OCP_V3_2_N
J 0
(5890 3935);
DISPLAY 0.553191 (5890 3935);
PAINT WHITE (5890 3935);
WIRE 16 -1 (6725 3825)(5125 3825);
FORCEPROP 2 LAST SIG_NAME RST_PERST1_OCP_V3_2_N
J 0
(5890 3835);
DISPLAY 0.553191 (5890 3835);
PAINT WHITE (5890 3835);
WIRE 16 -1 (5125 3775)(6725 3775);
FORCEPROP 2 LAST SIG_NAME OCP_V3_2_PRSNT2_R_N
J 0
(5890 3785);
DISPLAY 0.553191 (5890 3785);
PAINT WHITE (5890 3785);
WIRE 16 -1 (5125 3675)(6725 3675);
FORCEPROP 2 LAST SIG_NAME CLK_100M_CPU1_CLK03_DN
J 0
(5890 3685);
DISPLAY 0.553191 (5890 3685);
PAINT WHITE (5890 3685);
WIRE 16 -1 (6475 3975)(7625 3975);
FORCEPROP 2 LAST SIG_NAME SMB_OCP_V3_2_3V3AUX_BUF_SDA
J 0
(6940 3985);
DISPLAY 0.553191 (6940 3985);
PAINT WHITE (6940 3985);
WIRE 16 -1 (5125 3525)(5700 3525);
WIRE 16 -1 (5125 3625)(6725 3625);
FORCEPROP 2 LAST SIG_NAME CLK_100M_CPU1_CLK03_DP
J 0
(5890 3635);
DISPLAY 0.553191 (5890 3635);
PAINT WHITE (5890 3635);
WIRE 16 -1 (3775 -450)(4200 -450);
WIRE 16 -1 (4200 -275)(4200 -450);
WIRE 16 -1 (4200 -275)(4200 -100);
WIRE 16 -1 (3750 -275)(4200 -275);
WIRE 16 -1 (4200 0)(4200 -100);
WIRE 16 -1 (3750 -100)(4200 -100);
WIRE 16 -1 (3825 4125)(3525 4125);
WIRE 16 -1 (3525 4175)(3525 4125);
WIRE 16 -1 (3525 4125)(3525 4075);
WIRE 16 -1 (3525 4075)(3825 4075);
WIRE 16 -1 (3825 4175)(3525 4175);
WIRE 16 -1 (3525 4225)(3525 4175);
WIRE 16 -1 (3825 4225)(3525 4225);
WIRE 16 -1 (3525 4275)(3525 4225);
WIRE 16 -1 (3825 4275)(3525 4275);
WIRE 16 -1 (3525 4325)(3525 4275);
WIRE 16 -1 (3525 5400)(3525 4325);
WIRE 16 -1 (3825 4325)(3525 4325);
WIRE 16 -1 (3825 4675)(3650 4675);
WIRE 16 -1 (3650 4525)(3650 4675);
WIRE 16 -1 (3825 4525)(3650 4525);
WIRE 16 -1 (3650 3725)(3650 4525);
WIRE 16 -1 (3825 3725)(3650 3725);
WIRE 16 -1 (3650 3575)(3650 3725);
WIRE 16 -1 (3825 3575)(3650 3575);
WIRE 16 -1 (3650 3575)(3650 3425);
WIRE 16 -1 (3825 3425)(3650 3425);
WIRE 16 -1 (3650 3425)(3650 3275);
WIRE 16 -1 (3825 3275)(3650 3275);
WIRE 16 -1 (3650 3275)(3650 3125);
WIRE 16 -1 (3825 3125)(3650 3125);
WIRE 16 -1 (3650 3125)(3650 2975);
WIRE 16 -1 (3825 2975)(3650 2975);
WIRE 16 -1 (3650 2975)(3650 2825);
WIRE 16 -1 (3825 2825)(3650 2825);
WIRE 16 -1 (3650 2825)(3650 2675);
WIRE 16 -1 (3825 2675)(3650 2675);
WIRE 16 -1 (3650 2675)(3650 2525);
WIRE 16 -1 (3825 2525)(3650 2525);
WIRE 16 -1 (3650 2525)(3650 2375);
WIRE 16 -1 (3825 2375)(3650 2375);
WIRE 16 -1 (3650 2375)(3650 2225);
WIRE 16 -1 (3825 2225)(3650 2225);
WIRE 16 -1 (3650 2225)(3650 2025);
WIRE 16 -1 (3825 2025)(3650 2025);
WIRE 16 -1 (3650 2025)(3650 1875);
WIRE 16 -1 (3825 1875)(3650 1875);
WIRE 16 -1 (3650 1875)(3650 1725);
WIRE 16 -1 (3825 1725)(3650 1725);
WIRE 16 -1 (3650 1725)(3650 1575);
WIRE 16 -1 (3825 1575)(3650 1575);
WIRE 16 -1 (3650 1575)(3650 1425);
WIRE 16 -1 (3825 1425)(3650 1425);
WIRE 16 -1 (3650 1425)(3650 1275);
WIRE 16 -1 (3825 1275)(3650 1275);
WIRE 16 -1 (3650 1275)(3650 1125);
WIRE 16 -1 (3825 1125)(3650 1125);
WIRE 16 -1 (3650 1125)(3650 975);
WIRE 16 -1 (3825 975)(3650 975);
WIRE 16 -1 (3650 975)(3650 825);
WIRE 16 -1 (3825 825)(3650 825);
WIRE 16 -1 (3650 825)(3650 225);
WIRE 16 -1 (300 2850)(625 2850);
WIRE 16 -1 (300 2850)(300 2750);
WIRE 16 -1 (625 2750)(300 2750);
WIRE 16 -1 (300 2750)(300 2550);
WIRE 16 -1 (675 2550)(300 2550);
WIRE 16 -1 (300 2550)(300 2450);
WIRE 16 -1 (750 400)(750 500);
WIRE 16 -1 (750 500)(275 500);
WIRE 16 -1 (275 550)(275 500);
WIRE 16 -1 (275 500)(275 400);
WIRE 16 -1 (7900 -400)(7900 -525);
WIRE 16 -1 (7900 -525)(8150 -525);
WIRE 16 -1 (8425 -525)(8150 -525);
WIRE 16 -1 (8150 -525)(8150 -400);
WIRE 16 -1 (8425 -525)(8425 -400);
WIRE 16 -1 (8700 -525)(8425 -525);
WIRE 16 -1 (8700 -525)(8700 -400);
WIRE 16 -1 (8700 -575)(8700 -525);
WIRE 16 -1 (5700 -400)(5700 -525);
WIRE 16 -1 (5700 -525)(5975 -525);
WIRE 16 -1 (6375 -525)(5975 -525);
WIRE 16 -1 (5975 -525)(5975 -400);
WIRE 16 -1 (6375 -525)(6375 -400);
WIRE 16 -1 (6375 -525)(6650 -525);
WIRE 16 -1 (6925 -525)(6650 -525);
WIRE 16 -1 (6650 -525)(6650 -400);
WIRE 16 -1 (6925 -525)(6925 -400);
WIRE 16 -1 (7150 -525)(6925 -525);
WIRE 16 -1 (7150 -525)(7400 -525);
WIRE 16 -1 (7150 -400)(7150 -525);
WIRE 16 -1 (7400 -525)(7400 -400);
WIRE 16 -1 (7400 -575)(7400 -525);
WIRE 16 -1 (3775 -625)(4200 -625);
WIRE 16 -1 (4200 -700)(4200 -625);
WIRE 16 -1 (8700 -75)(8700 -200);
WIRE 16 -1 (8425 -75)(8700 -75);
WIRE 16 -1 (8425 -75)(8425 -200);
WIRE 16 -1 (8150 -75)(8425 -75);
WIRE 16 -1 (8150 -75)(8150 -200);
WIRE 16 -1 (7900 -75)(8150 -75);
WIRE 16 -1 (7900 0)(7900 -75);
WIRE 16 -1 (7900 -75)(7900 -200);
WIRE 16 -1 (7400 -75)(7400 -200);
WIRE 16 -1 (7150 -75)(7400 -75);
WIRE 16 -1 (7150 -200)(7150 -75);
WIRE 16 -1 (6925 -75)(7150 -75);
WIRE 16 -1 (6925 -75)(6925 -200);
WIRE 16 -1 (6650 -75)(6925 -75);
WIRE 16 -1 (6650 -75)(6650 -200);
WIRE 16 -1 (6375 -75)(6650 -75);
WIRE 16 -1 (6375 -75)(6375 -200);
WIRE 16 -1 (6375 -75)(5975 -75);
WIRE 16 -1 (5975 -75)(5975 -200);
WIRE 16 -1 (5700 -75)(5975 -75);
WIRE 16 -1 (5700 0)(5700 -75);
WIRE 16 -1 (5700 -200)(5700 -75);
WIRE 16 -1 (2550 4975)(3825 4975);
FORCEPROP 2 LAST SIG_NAME SGPIO_OCP_V3_2_DATAIN
J 0
(2615 4985);
DISPLAY 0.553191 (2615 4985);
PAINT WHITE (2615 4985);
WIRE 16 -1 (2550 5025)(3825 5025);
FORCEPROP 2 LAST SIG_NAME SGPIO_OCP_V3_2_LD_N
J 0
(2615 5035);
DISPLAY 0.553191 (2615 5035);
PAINT WHITE (2615 5035);
WIRE 16 -1 (2050 5075)(3825 5075);
FORCEPROP 2 LAST SIG_NAME OCP_V3_2_MAIN_PWR_EN_R
J 0
(2615 5085);
DISPLAY 0.553191 (2615 5085);
PAINT WHITE (2615 5085);
FORCEPROP 2 LASTPROP $XRERR UNIQUE?
J 0
(2375 5085);
DISPLAY 0.638298 (2375 5085);
PAINT MONO (2375 5085);
DISPLAY INVISIBLE (2375 5085);
WIRE 16 -1 (2050 3975)(3825 3975);
FORCEPROP 2 LAST SIG_NAME OCP_V3_2_BIF1_R_N
J 0
(2665 3985);
DISPLAY 0.553191 (2665 3985);
PAINT WHITE (2665 3985);
FORCEPROP 2 LASTPROP $XRERR UNIQUE?
J 0
(2425 3985);
DISPLAY 0.638298 (2425 3985);
PAINT MONO (2425 3985);
DISPLAY INVISIBLE (2425 3985);
WIRE 16 -1 (1850 5075)(825 5075);
FORCEPROP 2 LAST SIG_NAME OCP_V3_2_MAIN_PWR_EN
J 0
(890 5085);
DISPLAY 0.553191 (890 5085);
PAINT WHITE (890 5085);
WIRE 16 -1 (1050 4025)(1850 4025);
FORCEPROP 2 LAST SIG_NAME OCP_V3_2_ISO_BIF0_EN
J 0
(1115 4035);
DISPLAY 0.553191 (1115 4035);
PAINT WHITE (1115 4035);
WIRE 16 -1 (1050 3975)(1850 3975);
FORCEPROP 2 LAST SIG_NAME OCP_V3_2_ISO_BIF1_EN
J 0
(1115 3985);
DISPLAY 0.553191 (1115 3985);
PAINT WHITE (1115 3985);
WIRE 16 -1 (1050 3925)(1850 3925);
FORCEPROP 2 LAST SIG_NAME OCP_V3_2_ISO_BIF2_EN
J 0
(1115 3935);
DISPLAY 0.553191 (1115 3935);
PAINT WHITE (1115 3935);
WIRE 16 -1 (1050 3875)(3825 3875);
FORCEPROP 2 LAST SIG_NAME RST_PERST0_OCP_V3_2_N
J 0
(1115 3885);
DISPLAY 0.553191 (1115 3885);
PAINT WHITE (1115 3885);
WIRE 16 -1 (2050 4025)(3825 4025);
FORCEPROP 2 LAST SIG_NAME OCP_V3_2_BIF0_R_N
J 0
(2665 4035);
DISPLAY 0.553191 (2665 4035);
PAINT WHITE (2665 4035);
FORCEPROP 2 LASTPROP $XRERR UNIQUE?
J 0
(2425 4035);
DISPLAY 0.638298 (2425 4035);
PAINT MONO (2425 4035);
DISPLAY INVISIBLE (2425 4035);
WIRE 16 -1 (3825 3775)(2050 3775);
FORCEPROP 2 LAST SIG_NAME OCP_V3_2_AUX_PWR_EN_R
J 0
(2490 3785);
DISPLAY 0.553191 (2490 3785);
PAINT WHITE (2490 3785);
FORCEPROP 2 LASTPROP $XRERR UNIQUE?
J 0
(2250 3785);
DISPLAY 0.638298 (2250 3785);
PAINT MONO (2250 3785);
DISPLAY INVISIBLE (2250 3785);
WIRE 16 -1 (2425 3675)(3825 3675);
FORCEPROP 2 LAST SIG_NAME CLK_100M_CPU1_CLK02_DN
J 0
(2490 3685);
DISPLAY 0.553191 (2490 3685);
PAINT WHITE (2490 3685);
WIRE 16 -1 (2425 3625)(3825 3625);
FORCEPROP 2 LAST SIG_NAME CLK_100M_CPU1_CLK02_DP
J 0
(2490 3635);
DISPLAY 0.553191 (2490 3635);
PAINT WHITE (2490 3635);
WIRE 16 -1 (6200 5125)(5125 5125);
FORCEPROP 2 LAST SIG_NAME RST_PERST2_OCP_V3_2_N
J 0
(5415 5135);
DISPLAY 0.553191 (5415 5135);
PAINT WHITE (5415 5135);
WIRE 16 -1 (5125 3375)(5700 3375);
WIRE 16 -1 (5125 3475)(5550 3475);
WIRE 16 -1 (5125 2175)(6700 2175);
FORCEPROP 2 LAST SIG_NAME OCP_V3_2_PRSNT1_R_N
J 0
(5865 2185);
DISPLAY 0.680851 (5865 2185);
PAINT WHITE (5865 2185);
WIRE 16 -1 (5125 2325)(5700 2325);
WIRE 16 -1 (5125 2275)(5550 2275);
WIRE 16 -1 (5125 1925)(5550 1925);
WIRE 16 -1 (5700 1975)(5125 1975);
WIRE 16 -1 (6950 775)(8275 775);
FORCEPROP 2 LAST SIG_NAME USB2_CPU0_P10_DN
J 0
(7415 785);
DISPLAY 0.638298 (7415 785);
PAINT WHITE (7415 785);
WIRE 16 -1 (8275 725)(6950 725);
FORCEPROP 2 LAST SIG_NAME USB2_CPU0_P10_DP
J 0
(7415 735);
DISPLAY 0.638298 (7415 735);
PAINT WHITE (7415 735);
WIRE 16 -1 (5125 675)(6375 675);
FORCEPROP 2 LAST SIG_NAME OCP_V3_2_PWRBRK_N
J 0
(5615 685);
DISPLAY 0.638298 (5615 685);
PAINT WHITE (5615 685);
WIRE 16 -1 (5125 775)(6750 775);
FORCEPROP 2 LAST SIG_NAME USB2_P10_DN
J 0
(5615 785);
DISPLAY 0.638298 (5615 785);
PAINT WHITE (5615 785);
FORCEPROP 2 LASTPROP $XRERR UNIQUE?
J 0
(5375 785);
DISPLAY 0.638298 (5375 785);
PAINT MONO (5375 785);
DISPLAY INVISIBLE (5375 785);
WIRE 16 -1 (5125 725)(6750 725);
FORCEPROP 2 LAST SIG_NAME USB2_P10_DP
J 0
(5615 735);
DISPLAY 0.638298 (5615 735);
PAINT WHITE (5615 735);
FORCEPROP 2 LASTPROP $XRERR UNIQUE?
J 0
(5375 735);
DISPLAY 0.638298 (5375 735);
PAINT MONO (5375 735);
DISPLAY INVISIBLE (5375 735);
WIRE 16 -1 (2450 -100)(3550 -100);
FORCEPROP 2 LAST SIG_NAME SGPIO_OCP_V3_2_LD_N
J 0
(2565 -90);
DISPLAY 0.680851 (2565 -90);
PAINT WHITE (2565 -90);
WIRE 16 -1 (2250 675)(3825 675);
FORCEPROP 2 LAST SIG_NAME OCP_V3_2_PRSNT3_R_N
J 0
(2315 685);
DISPLAY 0.680851 (2315 685);
PAINT WHITE (2315 685);
WIRE 16 -1 (2100 725)(3825 725);
FORCEPROP 2 LAST SIG_NAME TP_OCP_V3_2_B69
J 0
(2165 735);
DISPLAY 0.680851 (2165 735);
PAINT WHITE (2165 735);
FORCEPROP 2 LASTPROP $XRERR UNIQUE?
J 0
(1860 725);
DISPLAY 0.638298 (1860 725);
PAINT MONO (1860 725);
DISPLAY INVISIBLE (1860 725);
WIRE 16 -1 (2100 775)(3825 775);
FORCEPROP 2 LAST SIG_NAME TP_OCP_V3_2_B68
J 0
(2165 785);
DISPLAY 0.680851 (2165 785);
PAINT WHITE (2165 785);
FORCEPROP 2 LASTPROP $XRERR UNIQUE?
J 0
(1860 775);
DISPLAY 0.638298 (1860 775);
PAINT MONO (1860 775);
DISPLAY INVISIBLE (1860 775);
WIRE 16 -1 (2425 2175)(3825 2175);
FORCEPROP 2 LAST SIG_NAME OCP_V3_2_PRSNT0_R_N
J 0
(2490 2185);
DISPLAY 0.553191 (2490 2185);
PAINT WHITE (2490 2185);
WIRE 16 -1 (2025 2850)(825 2850);
FORCEPROP 0 LAST CDS_PHYS_NET_NAME OCP_V3_2_AUX_PWR_EN
J 0
(1190 2892);
PAINT MONO (1190 2892);
DISPLAY INVISIBLE (1190 2892);
FORCEPROP 2 LAST SIG_NAME OCP_V3_2_AUX_PWR_EN
J 0
(1265 2860);
DISPLAY 0.680851 (1265 2860);
PAINT WHITE (1265 2860);
WIRE 16 -1 (5125 5025)(6200 5025);
FORCEPROP 2 LAST SIG_NAME IRQ_LVC3_OCP_V3_2_WAKE_N
J 0
(5415 5035);
DISPLAY 0.553191 (5415 5035);
PAINT WHITE (5415 5035);
WIRE 16 -1 (3300 3525)(3825 3525);
WIRE 16 -1 (3300 3225)(3825 3225);
WIRE 16 -1 (3150 3325)(3825 3325);
WIRE 16 -1 (3300 3375)(3825 3375);
WIRE 16 -1 (3150 3475)(3825 3475);
WIRE 16 -1 (2450 -275)(3550 -275);
FORCEPROP 2 LAST SIG_NAME SGPIO_OCP_V3_2_DATAIN
J 0
(2565 -265);
DISPLAY 0.680851 (2565 -265);
PAINT WHITE (2565 -265);
WIRE 16 -1 (2450 -625)(3575 -625);
FORCEPROP 2 LAST SIG_NAME SGPIO_OCP_V3_2_DATAOUT
J 0
(2565 -615);
DISPLAY 0.680851 (2565 -615);
PAINT WHITE (2565 -615);
WIRE 16 -1 (2450 -450)(3575 -450);
FORCEPROP 2 LAST SIG_NAME SGPIO_OCP_V3_2_CLK
J 0
(2565 -440);
DISPLAY 0.680851 (2565 -440);
PAINT WHITE (2565 -440);
WIRE 16 -1 (275 50)(1300 50);
FORCEPROP 2 LAST SIG_NAME OCP_V3_2_ID0
J 0
(865 60);
DISPLAY 0.680851 (865 60);
PAINT WHITE (865 60);
WIRE 16 -1 (275 50)(275 200);
WIRE 16 -1 (275 -125)(275 50);
WIRE 16 -1 (750 0)(1300 0);
FORCEPROP 2 LAST SIG_NAME OCP_V3_2_ID1
J 0
(865 10);
DISPLAY 0.680851 (865 10);
PAINT WHITE (865 10);
WIRE 16 -1 (750 -125)(750 0);
WIRE 16 -1 (750 200)(750 0);
WIRE 16 -1 (2025 2750)(825 2750);
FORCEPROP 0 LAST CDS_PHYS_NET_NAME OCP_V3_2_MAIN_PWR_EN
J 0
(1190 2792);
PAINT MONO (1190 2792);
DISPLAY INVISIBLE (1190 2792);
FORCEPROP 2 LAST SIG_NAME OCP_V3_2_MAIN_PWR_EN
J 0
(1265 2760);
DISPLAY 0.680851 (1265 2760);
PAINT WHITE (1265 2760);
WIRE 16 -1 (3825 875)(3150 875);
WIRE 16 -1 (3300 925)(3825 925);
WIRE 16 -1 (3150 1025)(3825 1025);
WIRE 16 -1 (3300 1075)(3825 1075);
WIRE 16 -1 (3150 1175)(3825 1175);
WIRE 16 -1 (3300 1225)(3825 1225);
WIRE 16 -1 (3150 1325)(3825 1325);
WIRE 16 -1 (5125 1075)(5700 1075);
WIRE 16 -1 (5125 1175)(5550 1175);
WIRE 16 -1 (5125 1225)(5700 1225);
WIRE 16 -1 (5125 1475)(5550 1475);
WIRE 16 -1 (5125 1625)(5550 1625);
WIRE 16 -1 (5125 1675)(5700 1675);
WIRE 16 -1 (5125 1775)(5550 1775);
WIRE 16 -1 (5125 1825)(5700 1825);
WIRE 16 -1 (5125 2425)(5550 2425);
WIRE 16 -1 (5125 2475)(5700 2475);
WIRE 16 -1 (5125 2575)(5550 2575);
WIRE 16 -1 (5125 2625)(5700 2625);
WIRE 16 -1 (5125 2725)(5550 2725);
WIRE 16 -1 (5125 2775)(5700 2775);
WIRE 16 -1 (5125 3025)(5550 3025);
WIRE 16 -1 (5125 3175)(5550 3175);
WIRE 16 -1 (5125 3225)(5700 3225);
WIRE 16 -1 (5125 3325)(5550 3325);
WIRE 16 -1 (6200 5075)(5125 5075);
FORCEPROP 2 LAST SIG_NAME RST_PERST3_OCP_V3_2_N
J 0
(5415 5085);
DISPLAY 0.553191 (5415 5085);
PAINT WHITE (5415 5085);
WIRE 16 -1 (3300 1375)(3825 1375);
WIRE 16 -1 (3150 1475)(3825 1475);
WIRE 16 -1 (3300 1525)(3825 1525);
WIRE 16 -1 (3150 1625)(3825 1625);
WIRE 16 -1 (3300 1675)(3825 1675);
WIRE 16 -1 (3150 1775)(3825 1775);
WIRE 16 -1 (3300 1825)(3825 1825);
WIRE 16 -1 (3150 1925)(3825 1925);
WIRE 16 -1 (3300 1975)(3825 1975);
WIRE 16 -1 (3150 2275)(3825 2275);
WIRE 16 -1 (3300 2325)(3825 2325);
WIRE 16 -1 (3150 2425)(3825 2425);
WIRE 16 -1 (3300 2475)(3825 2475);
WIRE 16 -1 (3150 2575)(3825 2575);
WIRE 16 -1 (3300 2625)(3825 2625);
WIRE 16 -1 (3150 2725)(3825 2725);
WIRE 16 -1 (3300 2775)(3825 2775);
WIRE 16 -1 (3150 3025)(3825 3025);
WIRE 16 -1 (3300 3075)(3825 3075);
WIRE 16 -1 (3150 3175)(3825 3175);
WIRE 16 -1 (2550 4925)(3825 4925);
FORCEPROP 2 LAST SIG_NAME SGPIO_OCP_V3_2_DATAOUT
J 0
(2615 4935);
DISPLAY 0.553191 (2615 4935);
PAINT WHITE (2615 4935);
WIRE 16 -1 (5700 3075)(5125 3075);
WIRE 16 -1 (2075 2550)(875 2550);
FORCEPROP 0 LAST CDS_PHYS_NET_NAME FM_OCP_V3_2_PWR_GOOD
J 0
(1240 2592);
PAINT MONO (1240 2592);
DISPLAY INVISIBLE (1240 2592);
FORCEPROP 2 LAST SIG_NAME FM_OCP_V3_2_PWR_GOOD
J 0
(1315 2560);
DISPLAY 0.680851 (1315 2560);
PAINT WHITE (1315 2560);
WIRE 16 -1 (5125 925)(5700 925);
WIRE 16 -1 (5700 1525)(5125 1525);
WIRE 16 -1 (5125 875)(5550 875);
WIRE 16 -1 (5125 1375)(5700 1375);
WIRE 16 -1 (5125 4975)(6200 4975);
FORCEPROP 2 LAST SIG_NAME OCP_V3_2_ISO1_RBT_ARB_IN
J 0
(5415 4985);
DISPLAY 0.553191 (5415 4985);
PAINT WHITE (5415 4985);
WIRE 16 -1 (5125 1025)(5550 1025);
WIRE 16 -1 (5125 1325)(5550 1325);
WIRE 16 -1 (1050 3775)(1850 3775);
FORCEPROP 2 LAST SIG_NAME OCP_V3_2_AUX_PWR_EN
J 0
(1115 3785);
DISPLAY 0.553191 (1115 3785);
PAINT WHITE (1115 3785);
WIRE 16 -1 (2550 4875)(3825 4875);
FORCEPROP 2 LAST SIG_NAME SGPIO_OCP_V3_2_CLK
J 0
(2615 4885);
DISPLAY 0.553191 (2615 4885);
PAINT WHITE (2615 4885);
WIRE 16 -1 (2550 4825)(3825 4825);
FORCEPROP 2 LAST SIG_NAME OCP_V3_2_ID0
J 0
(2615 4835);
DISPLAY 0.553191 (2615 4835);
PAINT WHITE (2615 4835);
WIRE 16 -1 (2550 4775)(3825 4775);
FORCEPROP 2 LAST SIG_NAME NCSI_OCP_V3_2_RXD1
J 0
(2615 4785);
DISPLAY 0.553191 (2615 4785);
PAINT WHITE (2615 4785);
WIRE 16 -1 (2550 4725)(3825 4725);
FORCEPROP 2 LAST SIG_NAME NCSI_OCP_V3_2_RXD0
J 0
(2615 4735);
DISPLAY 0.553191 (2615 4735);
PAINT WHITE (2615 4735);
WIRE 16 -1 (2050 3925)(3825 3925);
FORCEPROP 2 LAST SIG_NAME OCP_V3_2_BIF2_R_N
J 0
(2665 3935);
DISPLAY 0.553191 (2665 3935);
PAINT WHITE (2665 3935);
FORCEPROP 2 LASTPROP $XRERR UNIQUE?
J 0
(2425 3935);
DISPLAY 0.638298 (2425 3935);
PAINT MONO (2425 3935);
DISPLAY INVISIBLE (2425 3935);
WIRE 16 -1 (6275 3975)(5125 3975);
FORCEPROP 2 LAST SIG_NAME SMB_OCP_V3_2_3V3AUX_BUF_R_SDA
J 0
(5315 3985);
DISPLAY 0.553191 (5315 3985);
PAINT WHITE (5315 3985);
FORCEPROP 2 LASTPROP $XRERR UNIQUE?
J 0
(5075 3985);
DISPLAY 0.638298 (5075 3985);
PAINT MONO (5075 3985);
DISPLAY INVISIBLE (5075 3985);
DOT 1 (5300 4125);
DOT 1 (5300 425);
DOT 1 (5300 1425);
DOT 1 (5300 475);
DOT 1 (5300 575);
DOT 1 (300 2750);
DOT 1 (300 2550);
DOT 1 (750 0);
DOT 1 (275 500);
DOT 1 (275 50);
DOT 1 (8700 -525);
DOT 1 (8425 -75);
DOT 1 (8425 -525);
DOT 1 (8150 -75);
DOT 1 (8150 -525);
DOT 1 (7900 -75);
DOT 1 (7400 -525);
DOT 1 (7150 -525);
DOT 1 (7150 -75);
DOT 1 (6925 -75);
DOT 1 (6925 -525);
DOT 1 (6650 -75);
DOT 1 (6650 -525);
DOT 1 (6375 -525);
DOT 1 (6375 -75);
DOT 1 (5975 -75);
DOT 1 (5975 -525);
DOT 1 (5700 -75);
DOT 1 (4200 -100);
DOT 1 (4200 -275);
DOT 1 (3525 4325);
DOT 1 (3525 4225);
DOT 1 (5300 4175);
DOT 1 (5300 3725);
DOT 1 (5300 3575);
DOT 1 (5300 3425);
DOT 1 (3650 3425);
DOT 1 (5300 3275);
DOT 1 (3650 3275);
DOT 1 (5300 3125);
DOT 1 (3650 3125);
DOT 1 (5300 2975);
DOT 1 (3650 2975);
DOT 1 (5300 2825);
DOT 1 (3650 2825);
DOT 1 (5300 2675);
DOT 1 (3650 2675);
DOT 1 (5300 2525);
DOT 1 (3650 2525);
DOT 1 (5300 2375);
DOT 1 (3650 2375);
DOT 1 (5300 2225);
DOT 1 (3650 2225);
DOT 1 (5300 2025);
DOT 1 (3650 2025);
DOT 1 (5300 1875);
DOT 1 (3650 1875);
DOT 1 (5300 1725);
DOT 1 (3650 1725);
DOT 1 (5300 1575);
DOT 1 (3650 1575);
DOT 1 (3650 1425);
DOT 1 (5300 1275);
DOT 1 (3650 1275);
DOT 1 (5300 1125);
DOT 1 (3650 1125);
DOT 1 (5300 975);
DOT 1 (3650 975);
DOT 1 (5300 825);
DOT 1 (3650 825);
DOT 1 (5300 525);
DOT 1 (5300 375);
DOT 1 (5300 4525);
DOT 1 (3525 4125);
DOT 1 (3525 4275);
DOT 1 (3650 3575);
DOT 1 (3525 4175);
DOT 1 (5300 4225);
DOT 1 (5300 4325);
DOT 1 (3650 4525);
DOT 1 (3650 3725);
DOT 1 (5300 4075);
DOT 1 (5300 4275);
FORCENOTE
TO CPU1 PCIE G1 [15:0]
(5900 3375) 0;
DISPLAY LEFT (5900 3375);
DISPLAY 1.276596 (5900 3375);
PAINT SKYBLUE (5900 3375);
FORCENOTE
P/N SWAP
(2625 2725) 0;
DISPLAY LEFT (2625 2725);
DISPLAY 1.021277 (2625 2725);
FORCENOTE
P/N SWAP
(2625 1175) 0;
DISPLAY LEFT (2625 1175);
DISPLAY 1.021277 (2625 1175);
FORCENOTE
P/N SWAP
(2625 3175) 0;
DISPLAY LEFT (2625 3175);
DISPLAY 1.021277 (2625 3175);
FORCENOTE
P/N SWAP
(2625 3025) 0;
DISPLAY LEFT (2625 3025);
DISPLAY 1.021277 (2625 3025);
FORCENOTE
P/N SWAP
(2625 2425) 0;
DISPLAY LEFT (2625 2425);
DISPLAY 1.021277 (2625 2425);
FORCENOTE
P/N SWAP
(2625 1925) 0;
DISPLAY LEFT (2625 1925);
DISPLAY 1.021277 (2625 1925);
FORCENOTE
P/N SWAP
(2625 1775) 0;
DISPLAY LEFT (2625 1775);
DISPLAY 1.021277 (2625 1775);
FORCENOTE
P/N SWAP
(2625 1600) 0;
DISPLAY LEFT (2625 1600);
DISPLAY 1.021277 (2625 1600);
FORCENOTE
P/N SWAP
(2625 1475) 0;
DISPLAY LEFT (2625 1475);
DISPLAY 1.021277 (2625 1475);
FORCENOTE
P/N SWAP
(2625 1325) 0;
DISPLAY LEFT (2625 1325);
DISPLAY 1.021277 (2625 1325);
FORCENOTE
P/N SWAP
(2625 1025) 0;
DISPLAY LEFT (2625 1025);
DISPLAY 1.021277 (2625 1025);
FORCENOTE
P/N SWAP
(2625 900) 0;
DISPLAY LEFT (2625 900);
DISPLAY 1.021277 (2625 900);
FORCENOTE
FROM CPU1 PCIE G1 [15:0]
(350 3500) 0;
DISPLAY LEFT (350 3500);
DISPLAY 1.276596 (350 3500);
PAINT SKYBLUE (350 3500);
FORCENOTE
P/N SWAP
(2625 3300) 0;
DISPLAY LEFT (2625 3300);
DISPLAY 1.021277 (2625 3300);
FORCENOTE
P/N SWAP
(2625 3425) 0;
DISPLAY LEFT (2625 3425);
DISPLAY 1.021277 (2625 3425);
FORCENOTE
P/N SWAP
(2625 2575) 0;
DISPLAY LEFT (2625 2575);
DISPLAY 1.021277 (2625 2575);
FORCENOTE
P/N SWAP
(2625 2275) 0;
DISPLAY LEFT (2625 2275);
DISPLAY 1.021277 (2625 2275);
QUIT
